FILE_TYPE = MACRO_DRAWING;
SET COLOR_WIRE YELLOW;
SET COLOR_PROP ORANGE;
SET COLOR_DOT WHITE;
SET COLOR_ARC YELLOW;
SET COLOR_BODY GREEN;
SET COLOR_NOTE PURPLE;
SET PROP_DISPLAY VALUE;
SET PAGE_NUMBER P278;
FORCEADD OFFPAGE..1
(-450 4050);
FORCEPROP 2 LAST $XR2 294 
J 0
(-942 4050);
DISPLAY 0.638298 (-942 4050);
PAINT MONO (-942 4050);
FORCEPROP 2 LAST $XR1 293 
J 0
(-822 4050);
DISPLAY 0.638298 (-822 4050);
PAINT MONO (-822 4050);
FORCEPROP 2 LAST $XR0 292 
J 0
(-702 4050);
DISPLAY 0.638298 (-702 4050);
PAINT MONO (-702 4050);
FORCEPROP 1 LAST COMMENT_BODY TRUE
J 0
(-325 3950);
DISPLAY 0.872340 (-325 3950);
PAINT GREEN (-325 3950);
DISPLAY INVISIBLE (-325 3950);
FORCEPROP 1 LAST OFFPAGE TRUE
J 0
(-125 3925);
DISPLAY 0.872340 (-125 3925);
PAINT GREEN (-125 3925);
DISPLAY INVISIBLE (-125 3925);
FORCEPROP 2 LAST CDS_LIB standard
J 0
(-450 4050);
DISPLAY INVISIBLE (-450 4050);
FORCEPROP 2 LAST PATH I1
J 0
(-700 4100);
DISPLAY 1.021277 (-700 4100);
DISPLAY INVISIBLE (-700 4100);
FORCEADD OFFPAGE..1
(-175 8000);
FORCEPROP 2 LAST $XR1 296 
J 0
(-577 8000);
DISPLAY 0.638298 (-577 8000);
PAINT MONO (-577 8000);
FORCEPROP 2 LAST $XR0 241 
J 0
(-457 8000);
DISPLAY 0.638298 (-457 8000);
PAINT MONO (-457 8000);
FORCEPROP 1 LAST COMMENT_BODY TRUE
J 0
(-50 7900);
DISPLAY 0.872340 (-50 7900);
PAINT GREEN (-50 7900);
DISPLAY INVISIBLE (-50 7900);
FORCEPROP 1 LAST OFFPAGE TRUE
J 0
(150 7875);
DISPLAY 0.872340 (150 7875);
PAINT GREEN (150 7875);
DISPLAY INVISIBLE (150 7875);
FORCEPROP 2 LAST CDS_LIB standard
J 0
(-175 8000);
DISPLAY INVISIBLE (-175 8000);
FORCEPROP 2 LAST PATH I10
J 0
(-450 8050);
DISPLAY 1.021277 (-450 8050);
DISPLAY INVISIBLE (-450 8050);
FORCEADD UNIVERSAL_GND..1
R 3
(5650 8750);
FORCEPROP 3 LASTPIN (5600 8750) SIG_NAME GND\g
J 0
(5610 8760);
DISPLAY 0.659574 (5610 8760);
PAINT MONO (5610 8760);
DISPLAY INVISIBLE (5610 8760);
FORCEPROP 1 LAST HDL_POWER GND
R 1
J 1
(5725 8725);
DISPLAY 0.872340 (5725 8725);
PAINT GREEN (5725 8725);
DISPLAY INVISIBLE (5725 8725);
FORCEPROP 2 LAST CDS_LIB logical_power
J 0
(5650 8750);
PAINT MONO (5650 8750);
DISPLAY INVISIBLE (5650 8750);
FORCEPROP 1 LAST PATH I100
R 1
J 2
(5650 8675);
DISPLAY 0.872340 (5650 8675);
PAINT AQUA (5650 8675);
DISPLAY INVISIBLE (5650 8675);
FORCEADD OFFPAGE..2
(5650 8675);
FORCEPROP 2 LAST $XR2 294 
J 0
(6079 8675);
DISPLAY 0.638298 (6079 8675);
PAINT MONO (6079 8675);
FORCEPROP 2 LAST $XR1 293 
J 0
(5959 8675);
DISPLAY 0.638298 (5959 8675);
PAINT MONO (5959 8675);
FORCEPROP 2 LAST $XR0 292 
J 0
(5839 8675);
DISPLAY 0.638298 (5839 8675);
PAINT MONO (5839 8675);
FORCEPROP 1 LAST COMMENT_BODY TRUE
J 0
(5605 8580);
DISPLAY 0.872340 (5605 8580);
PAINT GREEN (5605 8580);
DISPLAY INVISIBLE (5605 8580);
FORCEPROP 1 LAST OFFPAGE TRUE
J 0
(5975 8550);
DISPLAY 0.872340 (5975 8550);
PAINT GREEN (5975 8550);
DISPLAY INVISIBLE (5975 8550);
FORCEPROP 2 LAST CDS_LIB standard
J 0
(5650 8675);
PAINT MONO (5650 8675);
DISPLAY INVISIBLE (5650 8675);
FORCEPROP 2 LAST PATH I101
J 0
(6100 8725);
DISPLAY 1.021277 (6100 8725);
DISPLAY INVISIBLE (6100 8725);
FORCEADD VCC15..1
(750 9400);
FORCEPROP 3 LASTPIN (750 9350) SIG_NAME P3V3_AUX\g
J 0
(760 9360);
DISPLAY 0.659574 (760 9360);
PAINT MONO (760 9360);
DISPLAY INVISIBLE (760 9360);
FORCEPROP 1 LAST HDL_POWER P3V3_AUX
J 1
(750 9450);
DISPLAY 0.617021 (750 9450);
PAINT GREEN (750 9450);
FORCEPROP 2 LAST CDS_LIB logical_power
J 0
(750 9400);
PAINT MONO (750 9400);
DISPLAY INVISIBLE (750 9400);
FORCEPROP 1 LAST PATH I102
J 0
(800 9425);
DISPLAY 0.872340 (800 9425);
PAINT AQUA (800 9425);
DISPLAY INVISIBLE (800 9425);
FORCEADD Q_RES..1
(1175 9150);
FORCEPROP 1 LAST PART_NUMBER CS00002JB13
J 0
(1300 9200);
DISPLAY 0.617021 (1300 9200);
PAINT BLUE (1300 9200);
DISPLAY INVISIBLE (1300 9200);
FORCEPROP 1 LAST TOLERANCE 5%
J 0
(1350 9150);
DISPLAY 0.617021 (1350 9150);
PAINT SKYBLUE (1350 9150);
FORCEPROP 1 LAST MATERIAL CHIP
J 0
(1300 9250);
DISPLAY 0.617021 (1300 9250);
PAINT SKYBLUE (1300 9250);
FORCEPROP 1 LAST VALUE 0
J 2
(1325 9150);
DISPLAY 0.617021 (1325 9150);
PAINT SKYBLUE (1325 9150);
FORCEPROP 1 LAST PACK_TYPE 0402LF
J 0
(1425 9150);
DISPLAY 0.617021 (1425 9150);
PAINT SKYBLUE (1425 9150);
FORCEPROP 1 LAST WATTAGE 1/16W
J 2
(1600 9250);
DISPLAY 0.617021 (1600 9250);
PAINT SKYBLUE (1600 9250);
FORCEPROP 1 LAST LOCATION R4781
J 0
(925 9150);
DISPLAY 0.617021 (925 9150);
PAINT AQUA (925 9150);
FORCEPROP 1 LASTPIN (1075 9150) $PN 1
J 0
(1087 9162);
DISPLAY 0.617021 (1087 9162);
PAINT MONO (1087 9162);
FORCEPROP 1 LASTPIN (1275 9150) $PN 2
J 0
(1237 9162);
DISPLAY 0.617021 (1237 9162);
PAINT MONO (1237 9162);
FORCEPROP 2 LAST CDS_LIB pure_quanta
J 0
(1175 9150);
DISPLAY INVISIBLE (1175 9150);
FORCEPROP 1 LAST PATH I103
J 0
(1125 9300);
DISPLAY 0.978723 (1125 9300);
PAINT WHITE (1125 9300);
DISPLAY INVISIBLE (1125 9300);
FORCEPROP 1 LAST LOCATION R4781
J 0
(1125 9250);
DISPLAY 1.021277 (1125 9250);
PAINT AQUA (1125 9250);
DISPLAY INVISIBLE (1125 9250);
FORCEPROP 0 LAST $SEC 1
J 0
(1125 9250);
DISPLAY 0.680851 (1125 9250);
PAINT MONO (1125 9250);
DISPLAY INVISIBLE (1125 9250);
FORCEPROP 0 LAST CDS_SEC 1
J 0
(1125 9250);
DISPLAY 1.021277 (1125 9250);
DISPLAY INVISIBLE (1125 9250);
FORCEADD Q_RES..1
(1175 9000);
FORCEPROP 1 LAST PART_NUMBER CS00002JB13
J 0
(1075 9050);
DISPLAY 0.319149 (1075 9050);
DISPLAY INVISIBLE (1075 9050);
FORCEPROP 1 LAST WATTAGE 1/16W
J 2
(1250 9075);
DISPLAY 0.319149 (1250 9075);
FORCEPROP 1 LAST PACK_TYPE 0402LF
J 0
(1075 9075);
DISPLAY 0.319149 (1075 9075);
FORCEPROP 1 LAST TOLERANCE 5%
J 0
(1375 9000);
DISPLAY 0.638298 (1375 9000);
FORCEPROP 1 LAST MATERIAL CHIP
J 0
(1450 9000);
DISPLAY 0.638298 (1450 9000);
FORCEPROP 1 LAST VALUE 0
J 2
(1350 9000);
DISPLAY 0.638298 (1350 9000);
FORCEPROP 1 LAST LOCATION R2558
J 0
(850 9000);
DISPLAY 0.638298 (850 9000);
FORCEPROP 1 LASTPIN (1075 9000) $PN 1
J 0
(1087 9012);
DISPLAY 0.787234 (1087 9012);
PAINT MONO (1087 9012);
FORCEPROP 1 LASTPIN (1275 9000) $PN 2
J 0
(1237 9012);
DISPLAY 0.787234 (1237 9012);
PAINT MONO (1237 9012);
FORCEPROP 2 LAST CDS_LIB pure_quanta
J 0
(1175 9000);
DISPLAY INVISIBLE (1175 9000);
FORCEPROP 2 LAST SEC_TYPE 0402LF
J 0
(1125 9200);
DISPLAY 1.021277 (1125 9200);
DISPLAY INVISIBLE (1125 9200);
FORCEPROP 1 LAST PATH I104
J 0
(1125 9150);
DISPLAY 0.978723 (1125 9150);
PAINT WHITE (1125 9150);
DISPLAY INVISIBLE (1125 9150);
FORCEPROP 2 LAST SEC 1
J 0
(1125 9200);
DISPLAY 0.680851 (1125 9200);
PAINT MONO (1125 9200);
DISPLAY INVISIBLE (1125 9200);
FORCEADD Q_RES..1
(1175 9300);
FORCEPROP 1 LAST PART_NUMBER CS21002FB06
J 0
(1300 9350);
DISPLAY 0.617021 (1300 9350);
PAINT BLUE (1300 9350);
DISPLAY INVISIBLE (1300 9350);
FORCEPROP 1 LAST MATERIAL CHIP
J 0
(1300 9400);
DISPLAY 0.617021 (1300 9400);
PAINT SKYBLUE (1300 9400);
FORCEPROP 1 LAST WATTAGE 1/16W
J 2
(1600 9400);
DISPLAY 0.617021 (1600 9400);
PAINT SKYBLUE (1600 9400);
FORCEPROP 1 LAST TOLERANCE 1%
J 0
(1375 9300);
DISPLAY 0.617021 (1375 9300);
PAINT SKYBLUE (1375 9300);
FORCEPROP 1 LAST VALUE 1K
J 2
(1350 9300);
DISPLAY 0.617021 (1350 9300);
PAINT SKYBLUE (1350 9300);
FORCEPROP 1 LAST PACK_TYPE 0402LF
J 0
(1475 9300);
DISPLAY 0.617021 (1475 9300);
PAINT SKYBLUE (1475 9300);
FORCEPROP 1 LAST LOCATION R2556
J 0
(925 9300);
DISPLAY 0.617021 (925 9300);
PAINT AQUA (925 9300);
FORCEPROP 1 LASTPIN (1075 9300) $PN 1
J 0
(1087 9312);
DISPLAY 0.617021 (1087 9312);
PAINT MONO (1087 9312);
FORCEPROP 1 LASTPIN (1275 9300) $PN 2
J 0
(1237 9312);
DISPLAY 0.617021 (1237 9312);
PAINT MONO (1237 9312);
FORCEPROP 2 LAST CDS_LIB pure_quanta
J 0
(1175 9300);
DISPLAY INVISIBLE (1175 9300);
FORCEPROP 1 LAST PATH I105
J 0
(1125 9450);
DISPLAY 0.978723 (1125 9450);
PAINT WHITE (1125 9450);
DISPLAY INVISIBLE (1125 9450);
FORCEPROP 1 LAST LOCATION R2556
J 0
(1125 9400);
DISPLAY 1.021277 (1125 9400);
PAINT AQUA (1125 9400);
DISPLAY INVISIBLE (1125 9400);
FORCEPROP 0 LAST $SEC 1
J 0
(1125 9400);
DISPLAY 0.680851 (1125 9400);
PAINT MONO (1125 9400);
DISPLAY INVISIBLE (1125 9400);
FORCEPROP 0 LAST CDS_SEC 1
J 0
(1125 9400);
DISPLAY 1.021277 (1125 9400);
DISPLAY INVISIBLE (1125 9400);
FORCEADD Q_CAP..2
(2025 9300);
FORCEPROP 1 LAST PART_NUMBER TMP_QCH21006JB10
J 1
(2300 9250);
DISPLAY 0.617021 (2300 9250);
PAINT BLUE (2300 9250);
DISPLAY INVISIBLE (2300 9250);
FORCEPROP 1 LAST TOLERANCE 5%
J 2
(2675 9250);
DISPLAY 0.617021 (2675 9250);
PAINT SKYBLUE (2675 9250);
FORCEPROP 1 LAST MATERIAL EMPTY
J 0
(2500 9300);
DISPLAY 0.617021 (2500 9300);
PAINT RED (2500 9300);
FORCEPROP 1 LAST VALUE 1000PF
J 2
(2350 9300);
DISPLAY 0.617021 (2350 9300);
PAINT SKYBLUE (2350 9300);
FORCEPROP 1 LAST VOLTAGE 50V
J 0
(2375 9300);
DISPLAY 0.617021 (2375 9300);
PAINT SKYBLUE (2375 9300);
FORCEPROP 1 LAST PACK_TYPE 0402
J 1
(2575 9200);
DISPLAY 0.617021 (2575 9200);
PAINT SKYBLUE (2575 9200);
FORCEPROP 1 LAST LOCATION C2450
J 1
(1825 9300);
DISPLAY 0.617021 (1825 9300);
PAINT AQUA (1825 9300);
FORCEPROP 1 LASTPIN (1925 9300) $PN 1
J 0
(1915 9315);
DISPLAY 0.617021 (1915 9315);
PAINT MONO (1915 9315);
FORCEPROP 1 LASTPIN (2125 9300) $PN 2
J 0
(2110 9315);
DISPLAY 0.617021 (2110 9315);
PAINT MONO (2110 9315);
FORCEPROP 2 LAST CDS_LIB pure_quanta
J 0
(2025 9300);
DISPLAY INVISIBLE (2025 9300);
FORCEPROP 1 LAST PATH I106
J 0
(2025 9500);
DISPLAY 0.978723 (2025 9500);
PAINT WHITE (2025 9500);
DISPLAY INVISIBLE (2025 9500);
FORCEPROP 1 LAST LOCATION C2450
J 0
(1975 9400);
DISPLAY 1.021277 (1975 9400);
PAINT AQUA (1975 9400);
DISPLAY INVISIBLE (1975 9400);
FORCEPROP 0 LAST $SEC 1
J 0
(1975 9400);
DISPLAY 0.680851 (1975 9400);
PAINT MONO (1975 9400);
DISPLAY INVISIBLE (1975 9400);
FORCEPROP 0 LAST CDS_SEC 1
J 0
(1975 9400);
DISPLAY 1.021277 (1975 9400);
DISPLAY INVISIBLE (1975 9400);
FORCEADD UNIVERSAL_GND..1
R 1
(2725 9300);
FORCEPROP 3 LASTPIN (2675 9300) SIG_NAME GND\g
J 0
(2685 9310);
DISPLAY 0.659574 (2685 9310);
PAINT MONO (2685 9310);
DISPLAY INVISIBLE (2685 9310);
FORCEPROP 1 LAST HDL_POWER GND
R 1
J 1
(2800 9325);
DISPLAY 0.872340 (2800 9325);
PAINT GREEN (2800 9325);
DISPLAY INVISIBLE (2800 9325);
FORCEPROP 2 LAST CDS_LIB logical_power
J 0
(2725 9300);
PAINT MONO (2725 9300);
DISPLAY INVISIBLE (2725 9300);
FORCEPROP 1 LAST PATH I107
R 1
J 0
(2725 9375);
DISPLAY 0.872340 (2725 9375);
PAINT AQUA (2725 9375);
DISPLAY INVISIBLE (2725 9375);
FORCEADD Q_RES..1
(5525 9150);
FORCEPROP 1 LAST PART_NUMBER CS-1002FB04
J 0
(5675 9100);
DISPLAY 0.617021 (5675 9100);
PAINT BLUE (5675 9100);
DISPLAY INVISIBLE (5675 9100);
FORCEPROP 1 LAST PACK_TYPE 0402LF
J 0
(5675 9050);
DISPLAY 0.617021 (5675 9050);
PAINT SKYBLUE (5675 9050);
FORCEPROP 1 LAST VALUE 1
J 2
(5700 9150);
DISPLAY 0.617021 (5700 9150);
PAINT SKYBLUE (5700 9150);
FORCEPROP 1 LAST MATERIAL CHIP
J 0
(5825 9150);
DISPLAY 0.617021 (5825 9150);
PAINT SKYBLUE (5825 9150);
FORCEPROP 1 LAST TOLERANCE 1%
J 0
(5725 9150);
DISPLAY 0.617021 (5725 9150);
PAINT SKYBLUE (5725 9150);
FORCEPROP 1 LAST WATTAGE 1/16W
J 2
(6025 9050);
DISPLAY 0.617021 (6025 9050);
PAINT SKYBLUE (6025 9050);
FORCEPROP 1 LAST LOCATION PR283
J 0
(5300 9150);
DISPLAY 0.617021 (5300 9150);
PAINT AQUA (5300 9150);
FORCEPROP 1 LASTPIN (5425 9150) $PN 1
J 0
(5437 9162);
DISPLAY 0.617021 (5437 9162);
PAINT MONO (5437 9162);
FORCEPROP 1 LASTPIN (5625 9150) $PN 2
J 0
(5587 9162);
DISPLAY 0.617021 (5587 9162);
PAINT MONO (5587 9162);
FORCEPROP 2 LAST CDS_LIB pure_quanta
J 0
(5525 9150);
DISPLAY INVISIBLE (5525 9150);
FORCEPROP 1 LAST PATH I108
J 0
(5475 9300);
DISPLAY 0.978723 (5475 9300);
PAINT WHITE (5475 9300);
DISPLAY INVISIBLE (5475 9300);
FORCEPROP 1 LAST LOCATION PR283
J 0
(5475 9250);
DISPLAY 1.021277 (5475 9250);
PAINT AQUA (5475 9250);
DISPLAY INVISIBLE (5475 9250);
FORCEPROP 0 LAST $SEC 1
J 0
(5475 9250);
DISPLAY 0.680851 (5475 9250);
PAINT MONO (5475 9250);
DISPLAY INVISIBLE (5475 9250);
FORCEPROP 0 LAST CDS_SEC 1
J 0
(5475 9250);
DISPLAY 1.021277 (5475 9250);
DISPLAY INVISIBLE (5475 9250);
FORCEADD VCC15..1
(6000 9275);
FORCEPROP 3 LASTPIN (6000 9225) SIG_NAME P3V3_AUX\g
J 0
(6010 9235);
DISPLAY 0.659574 (6010 9235);
PAINT MONO (6010 9235);
DISPLAY INVISIBLE (6010 9235);
FORCEPROP 1 LAST HDL_POWER P3V3_AUX
J 1
(6000 9325);
DISPLAY 0.617021 (6000 9325);
PAINT GREEN (6000 9325);
FORCEPROP 2 LAST CDS_LIB logical_power
J 0
(6000 9275);
DISPLAY INVISIBLE (6000 9275);
FORCEPROP 1 LAST PATH I109
J 0
(6050 9300);
DISPLAY 0.872340 (6050 9300);
PAINT AQUA (6050 9300);
DISPLAY INVISIBLE (6050 9300);
FORCEADD OFFPAGE..6
(-125 8550);
FORCEPROP 2 LAST $XR1 284 
J 0
(-494 8550);
DISPLAY 0.638298 (-494 8550);
PAINT MONO (-494 8550);
FORCEPROP 2 LAST $XR0 45 
J 0
(-374 8550);
DISPLAY 0.638298 (-374 8550);
PAINT MONO (-374 8550);
FORCEPROP 1 LAST COMMENT_BODY TRUE
J 0
(-25 8475);
DISPLAY 0.872340 (-25 8475);
PAINT GREEN (-25 8475);
DISPLAY INVISIBLE (-25 8475);
FORCEPROP 1 LAST OFFPAGE TRUE
J 0
(200 8425);
DISPLAY 0.872340 (200 8425);
PAINT GREEN (200 8425);
DISPLAY INVISIBLE (200 8425);
FORCEPROP 2 LAST CDS_LIB standard
J 0
(-125 8550);
DISPLAY INVISIBLE (-125 8550);
FORCEPROP 2 LAST PATH I11
J 0
(-350 8600);
DISPLAY 1.021277 (-350 8600);
DISPLAY INVISIBLE (-350 8600);
FORCEADD Q_RES..2
(625 3825);
FORCEPROP 1 LAST PART_NUMBER CS28452FB06
J 2
(575 3675);
DISPLAY 0.510638 (575 3675);
DISPLAY INVISIBLE (575 3675);
FORCEPROP 1 LAST PACK_TYPE 0402LF
J 2
(575 3625);
DISPLAY 0.510638 (575 3625);
FORCEPROP 1 LAST TOLERANCE 1%
J 2
(575 3825);
DISPLAY 0.510638 (575 3825);
FORCEPROP 1 LAST VALUE 8.45K
J 2
(575 3875);
DISPLAY 0.510638 (575 3875);
FORCEPROP 1 LAST WATTAGE 1/16W
J 2
(575 3775);
DISPLAY 0.510638 (575 3775);
FORCEPROP 1 LAST MATERIAL CHIP
J 2
(575 3725);
DISPLAY 0.510638 (575 3725);
FORCEPROP 1 LAST LOCATION PR259
J 2
(575 3925);
DISPLAY 0.510638 (575 3925);
FORCEPROP 1 LASTPIN (625 3925) $PN 1
J 0
(630 3887);
DISPLAY 0.787234 (630 3887);
PAINT MONO (630 3887);
FORCEPROP 1 LASTPIN (625 3725) $PN 2
J 0
(630 3735);
DISPLAY 0.787234 (630 3735);
PAINT MONO (630 3735);
FORCEPROP 1 LAST PATH I110
J 0
(675 4000);
DISPLAY 0.978723 (675 4000);
PAINT WHITE (675 4000);
DISPLAY INVISIBLE (675 4000);
FORCEPROP 2 LAST CDS_LIB pure_quanta
J 0
(625 3825);
DISPLAY INVISIBLE (625 3825);
FORCEPROP 0 LAST $SEC 1
J 0
(575 3950);
DISPLAY 0.680851 (575 3950);
PAINT MONO (575 3950);
DISPLAY INVISIBLE (575 3950);
FORCEPROP 0 LAST CDS_SEC 1
J 0
(575 3950);
DISPLAY 1.021277 (575 3950);
DISPLAY INVISIBLE (575 3950);
FORCEADD Q_CAP..1
(4450 8950);
FORCEPROP 1 LAST PART_NUMBER CH4104K1B00
J 0
(4500 8875);
DISPLAY 0.638298 (4500 8875);
DISPLAY INVISIBLE (4500 8875);
FORCEPROP 1 LAST TOLERANCE 10%
J 0
(4500 8925);
DISPLAY 0.638298 (4500 8925);
FORCEPROP 1 LAST PACK_TYPE 0402
J 0
(4500 8825);
DISPLAY 0.638298 (4500 8825);
FORCEPROP 1 LAST MATERIAL EMPTY
J 0
(4500 8900);
DISPLAY 0.638298 (4500 8900);
PAINT RED (4500 8900);
FORCEPROP 1 LAST VOLTAGE 25V
J 0
(4500 8975);
DISPLAY 0.638298 (4500 8975);
FORCEPROP 1 LAST VALUE 0.1UF
J 0
(4500 9025);
DISPLAY 0.638298 (4500 9025);
FORCEPROP 1 LAST LOCATION PC2367
J 0
(4500 9050);
DISPLAY 0.978723 (4500 9050);
FORCEPROP 1 LASTPIN (4450 9050) $PN 1
J 0
(4460 9030);
DISPLAY 0.787234 (4460 9030);
PAINT MONO (4460 9030);
FORCEPROP 1 LASTPIN (4450 8850) $PN 2
J 0
(4460 8830);
DISPLAY 0.787234 (4460 8830);
PAINT MONO (4460 8830);
FORCEPROP 1 LAST PATH I111
J 0
(4500 9100);
DISPLAY 0.978723 (4500 9100);
PAINT WHITE (4500 9100);
DISPLAY INVISIBLE (4500 9100);
FORCEPROP 2 LAST CDS_LIB pure_quanta
J 0
(4450 8950);
DISPLAY INVISIBLE (4450 8950);
FORCEPROP 0 LAST $SEC 1
J 0
(4500 9100);
DISPLAY 0.680851 (4500 9100);
PAINT MONO (4500 9100);
DISPLAY INVISIBLE (4500 9100);
FORCEPROP 0 LAST CDS_SEC 1
J 0
(4500 9100);
DISPLAY 1.021277 (4500 9100);
DISPLAY INVISIBLE (4500 9100);
FORCEADD OFFPAGE..5
(-125 8400);
FORCEPROP 2 LAST $XR1 284 
J 0
(-469 8400);
DISPLAY 0.638298 (-469 8400);
PAINT MONO (-469 8400);
FORCEPROP 2 LAST $XR0 45 
J 0
(-349 8400);
DISPLAY 0.638298 (-349 8400);
PAINT MONO (-349 8400);
FORCEPROP 1 LAST COMMENT_BODY TRUE
J 0
(-25 8325);
DISPLAY 0.872340 (-25 8325);
PAINT GREEN (-25 8325);
DISPLAY INVISIBLE (-25 8325);
FORCEPROP 1 LAST OFFPAGE TRUE
J 0
(200 8275);
DISPLAY 0.872340 (200 8275);
PAINT GREEN (200 8275);
DISPLAY INVISIBLE (200 8275);
FORCEPROP 2 LAST CDS_LIB standard
J 0
(-125 8400);
DISPLAY INVISIBLE (-125 8400);
FORCEPROP 2 LAST PATH I12
J 0
(-325 8450);
DISPLAY 1.021277 (-325 8450);
DISPLAY INVISIBLE (-325 8450);
FORCEADD OFFPAGE..1
(-125 8700);
FORCEPROP 2 LAST $XR1 284 
J 0
(-466 8700);
DISPLAY 0.638298 (-466 8700);
PAINT MONO (-466 8700);
FORCEPROP 2 LAST $XR0 45 
J 0
(-346 8700);
DISPLAY 0.638298 (-346 8700);
PAINT MONO (-346 8700);
FORCEPROP 1 LAST COMMENT_BODY TRUE
J 0
(0 8600);
DISPLAY 0.872340 (0 8600);
PAINT GREEN (0 8600);
DISPLAY INVISIBLE (0 8600);
FORCEPROP 1 LAST OFFPAGE TRUE
J 0
(200 8575);
DISPLAY 0.872340 (200 8575);
PAINT GREEN (200 8575);
DISPLAY INVISIBLE (200 8575);
FORCEPROP 2 LAST CDS_LIB standard
J 0
(-125 8700);
DISPLAY INVISIBLE (-125 8700);
FORCEPROP 2 LAST PATH I13
J 0
(-325 8750);
DISPLAY 1.021277 (-325 8750);
DISPLAY INVISIBLE (-325 8750);
FORCEADD Q_RES..1
(-100 8800);
FORCEPROP 1 LAST PART_NUMBER CS11002FB07
J 0
(25 8825);
DISPLAY 0.489362 (25 8825);
PAINT BLUE (25 8825);
DISPLAY INVISIBLE (25 8825);
FORCEPROP 1 LAST MATERIAL EMPTY
J 0
(175 8800);
DISPLAY 0.489362 (175 8800);
PAINT RED (175 8800);
FORCEPROP 1 LAST PACK_TYPE 0402LF
J 0
(25 8850);
DISPLAY 0.489362 (25 8850);
PAINT SKYBLUE (25 8850);
FORCEPROP 1 LAST WATTAGE 1/16W
J 2
(375 8850);
DISPLAY 0.489362 (375 8850);
PAINT SKYBLUE (375 8850);
FORCEPROP 1 LAST VALUE 100
J 2
(75 8800);
DISPLAY 0.489362 (75 8800);
PAINT SKYBLUE (75 8800);
FORCEPROP 1 LAST TOLERANCE 1%
J 0
(100 8800);
DISPLAY 0.489362 (100 8800);
PAINT SKYBLUE (100 8800);
FORCEPROP 1 LAST LOCATION R2354
J 0
(-325 8800);
DISPLAY 0.574468 (-325 8800);
PAINT AQUA (-325 8800);
FORCEPROP 1 LASTPIN (-200 8800) $PN 1
J 0
(-188 8812);
DISPLAY 0.617021 (-188 8812);
PAINT MONO (-188 8812);
FORCEPROP 1 LASTPIN (0 8800) $PN 2
J 0
(-38 8812);
DISPLAY 0.617021 (-38 8812);
PAINT MONO (-38 8812);
FORCEPROP 2 LAST CDS_LIB pure_quanta
J 0
(-100 8800);
DISPLAY INVISIBLE (-100 8800);
FORCEPROP 1 LAST PATH I14
J 0
(-150 8950);
DISPLAY 0.978723 (-150 8950);
PAINT WHITE (-150 8950);
DISPLAY INVISIBLE (-150 8950);
FORCEPROP 0 LAST $SEC 1
J 0
(225 8875);
DISPLAY 0.680851 (225 8875);
PAINT MONO (225 8875);
DISPLAY INVISIBLE (225 8875);
FORCEPROP 0 LAST CDS_SEC 1
J 0
(225 8875);
DISPLAY 1.021277 (225 8875);
DISPLAY INVISIBLE (225 8875);
FORCEADD Q_RES..1
(-100 8900);
FORCEPROP 1 LAST PART_NUMBER CS04992FB07
J 0
(25 8925);
DISPLAY 0.489362 (25 8925);
PAINT BLUE (25 8925);
DISPLAY INVISIBLE (25 8925);
FORCEPROP 1 LAST WATTAGE 1/16W
J 2
(375 8950);
DISPLAY 0.489362 (375 8950);
PAINT SKYBLUE (375 8950);
FORCEPROP 1 LAST MATERIAL EMPTY
J 0
(175 8900);
DISPLAY 0.489362 (175 8900);
PAINT RED (175 8900);
FORCEPROP 1 LAST PACK_TYPE 0402LF
J 0
(25 8950);
DISPLAY 0.489362 (25 8950);
PAINT SKYBLUE (25 8950);
FORCEPROP 1 LAST VALUE 49.9
J 2
(100 8900);
DISPLAY 0.489362 (100 8900);
PAINT SKYBLUE (100 8900);
FORCEPROP 1 LAST TOLERANCE 1%
J 0
(125 8900);
DISPLAY 0.489362 (125 8900);
PAINT SKYBLUE (125 8900);
FORCEPROP 1 LAST LOCATION R2345
J 0
(-325 8900);
DISPLAY 0.574468 (-325 8900);
PAINT AQUA (-325 8900);
FORCEPROP 1 LASTPIN (-200 8900) $PN 1
J 0
(-188 8912);
DISPLAY 0.617021 (-188 8912);
PAINT MONO (-188 8912);
FORCEPROP 1 LASTPIN (0 8900) $PN 2
J 0
(-38 8912);
DISPLAY 0.617021 (-38 8912);
PAINT MONO (-38 8912);
FORCEPROP 2 LAST CDS_LIB pure_quanta
J 0
(-100 8900);
DISPLAY INVISIBLE (-100 8900);
FORCEPROP 1 LAST PATH I15
J 0
(-150 9050);
DISPLAY 0.978723 (-150 9050);
PAINT WHITE (-150 9050);
DISPLAY INVISIBLE (-150 9050);
FORCEPROP 0 LAST $SEC 1
J 0
(225 8975);
DISPLAY 0.680851 (225 8975);
PAINT MONO (225 8975);
DISPLAY INVISIBLE (225 8975);
FORCEPROP 0 LAST CDS_SEC 1
J 0
(225 8975);
DISPLAY 1.021277 (225 8975);
DISPLAY INVISIBLE (225 8975);
FORCEADD VCC15..1
(-825 9025);
FORCEPROP 3 LASTPIN (-825 8975) SIG_NAME PVNN_TERM_CPU1\g
J 0
(-815 8985);
DISPLAY 0.659574 (-815 8985);
PAINT MONO (-815 8985);
DISPLAY INVISIBLE (-815 8985);
FORCEPROP 1 LAST HDL_POWER PVNN_TERM_CPU1
J 1
(-825 9075);
DISPLAY 0.617021 (-825 9075);
PAINT GREEN (-825 9075);
FORCEPROP 2 LAST CDS_LIB logical_power
J 0
(-825 9025);
DISPLAY INVISIBLE (-825 9025);
FORCEPROP 1 LAST PATH I16
J 0
(-775 9050);
DISPLAY 0.872340 (-775 9050);
PAINT AQUA (-775 9050);
DISPLAY INVISIBLE (-775 9050);
FORCEADD OFFPAGE..1
(-125 9000);
FORCEPROP 2 LAST $XR0 222 
J 0
(-377 9000);
DISPLAY 0.638298 (-377 9000);
PAINT MONO (-377 9000);
FORCEPROP 1 LAST COMMENT_BODY TRUE
J 0
(0 8900);
DISPLAY 0.872340 (0 8900);
PAINT GREEN (0 8900);
DISPLAY INVISIBLE (0 8900);
FORCEPROP 1 LAST OFFPAGE TRUE
J 0
(200 8875);
DISPLAY 0.872340 (200 8875);
PAINT GREEN (200 8875);
DISPLAY INVISIBLE (200 8875);
FORCEPROP 2 LAST CDS_LIB standard
J 0
(-125 9000);
DISPLAY INVISIBLE (-125 9000);
FORCEPROP 2 LAST PATH I17
J 0
(-375 9050);
DISPLAY 1.021277 (-375 9050);
DISPLAY INVISIBLE (-375 9050);
FORCEADD OFFPAGE..5
(-125 9150);
FORCEPROP 2 LAST $XR1 254 
J 0
(-500 9150);
DISPLAY 0.638298 (-500 9150);
PAINT MONO (-500 9150);
FORCEPROP 2 LAST $XR0 214 
J 0
(-380 9150);
DISPLAY 0.638298 (-380 9150);
PAINT MONO (-380 9150);
FORCEPROP 1 LAST COMMENT_BODY TRUE
J 0
(-25 9075);
DISPLAY 0.872340 (-25 9075);
PAINT GREEN (-25 9075);
DISPLAY INVISIBLE (-25 9075);
FORCEPROP 1 LAST OFFPAGE TRUE
J 0
(200 9025);
DISPLAY 0.872340 (200 9025);
PAINT GREEN (200 9025);
DISPLAY INVISIBLE (200 9025);
FORCEPROP 2 LAST CDS_LIB standard
J 0
(-125 9150);
DISPLAY INVISIBLE (-125 9150);
FORCEPROP 2 LAST PATH I18
J 0
(-375 9200);
DISPLAY 1.021277 (-375 9200);
DISPLAY INVISIBLE (-375 9200);
FORCEADD UNIVERSAL_GND..1
(625 3600);
FORCEPROP 3 LASTPIN (625 3650) SIG_NAME GND\g
J 0
(635 3660);
DISPLAY 0.659574 (635 3660);
PAINT MONO (635 3660);
DISPLAY INVISIBLE (635 3660);
FORCEPROP 1 LAST HDL_POWER GND
J 1
(650 3525);
DISPLAY 0.872340 (650 3525);
PAINT GREEN (650 3525);
DISPLAY INVISIBLE (650 3525);
FORCEPROP 2 LAST CDS_LIB logical_power
J 0
(625 3600);
PAINT MONO (625 3600);
DISPLAY INVISIBLE (625 3600);
FORCEPROP 1 LAST PATH I19
J 0
(700 3600);
DISPLAY 0.872340 (700 3600);
PAINT AQUA (700 3600);
DISPLAY INVISIBLE (700 3600);
FORCEADD OFFPAGE..5
(225 4350);
FORCEPROP 2 LAST $XR1 254 
J 0
(-150 4350);
DISPLAY 0.638298 (-150 4350);
PAINT MONO (-150 4350);
FORCEPROP 2 LAST $XR0 214 
J 0
(-30 4350);
DISPLAY 0.638298 (-30 4350);
PAINT MONO (-30 4350);
FORCEPROP 1 LAST COMMENT_BODY TRUE
J 0
(325 4275);
DISPLAY 0.872340 (325 4275);
PAINT GREEN (325 4275);
DISPLAY INVISIBLE (325 4275);
FORCEPROP 1 LAST OFFPAGE TRUE
J 0
(550 4225);
DISPLAY 0.872340 (550 4225);
PAINT GREEN (550 4225);
DISPLAY INVISIBLE (550 4225);
FORCEPROP 2 LAST CDS_LIB standard
J 0
(225 4350);
DISPLAY INVISIBLE (225 4350);
FORCEPROP 2 LAST PATH I2
J 0
(-25 4400);
DISPLAY 1.021277 (-25 4400);
DISPLAY INVISIBLE (-25 4400);
FORCEADD Q_RES..1
(1100 3700);
FORCEPROP 1 LAST PART_NUMBER CS00002JB13
J 0
(1225 3650);
DISPLAY 0.617021 (1225 3650);
PAINT BLUE (1225 3650);
DISPLAY INVISIBLE (1225 3650);
FORCEPROP 1 LAST PACK_TYPE 0402LF
J 0
(1350 3700);
DISPLAY 0.617021 (1350 3700);
PAINT SKYBLUE (1350 3700);
FORCEPROP 1 LAST TOLERANCE 5%
J 0
(1275 3700);
DISPLAY 0.617021 (1275 3700);
PAINT SKYBLUE (1275 3700);
FORCEPROP 1 LAST VALUE 0
J 2
(1250 3700);
DISPLAY 0.617021 (1250 3700);
PAINT SKYBLUE (1250 3700);
FORCEPROP 1 LAST MATERIAL CHIP
J 0
(1225 3600);
DISPLAY 0.617021 (1225 3600);
PAINT SKYBLUE (1225 3600);
FORCEPROP 1 LAST WATTAGE 1/16W
J 2
(1525 3600);
DISPLAY 0.617021 (1525 3600);
PAINT SKYBLUE (1525 3600);
FORCEPROP 1 LAST LOCATION PR261
J 0
(900 3700);
DISPLAY 0.617021 (900 3700);
PAINT AQUA (900 3700);
FORCEPROP 1 LASTPIN (1000 3700) $PN 1
J 0
(1012 3712);
DISPLAY 0.617021 (1012 3712);
PAINT MONO (1012 3712);
FORCEPROP 1 LASTPIN (1200 3700) $PN 2
J 0
(1162 3712);
DISPLAY 0.617021 (1162 3712);
PAINT MONO (1162 3712);
FORCEPROP 2 LAST CDS_LIB pure_quanta
J 0
(1100 3700);
DISPLAY INVISIBLE (1100 3700);
FORCEPROP 1 LAST PATH I21
J 0
(1050 3850);
DISPLAY 0.978723 (1050 3850);
PAINT WHITE (1050 3850);
DISPLAY INVISIBLE (1050 3850);
FORCEPROP 1 LAST LOCATION PR261
J 0
(1050 3800);
DISPLAY 1.021277 (1050 3800);
PAINT AQUA (1050 3800);
DISPLAY INVISIBLE (1050 3800);
FORCEPROP 0 LAST $SEC 1
J 0
(1050 3800);
DISPLAY 0.680851 (1050 3800);
PAINT MONO (1050 3800);
DISPLAY INVISIBLE (1050 3800);
FORCEPROP 0 LAST CDS_SEC 1
J 0
(1050 3800);
DISPLAY 1.021277 (1050 3800);
DISPLAY INVISIBLE (1050 3800);
FORCEADD Q_RES..1
(1100 3800);
FORCEPROP 1 LAST PART_NUMBER CS00002JB13
J 0
(1225 3750);
DISPLAY 0.510638 (1225 3750);
PAINT BLUE (1225 3750);
DISPLAY INVISIBLE (1225 3750);
FORCEPROP 1 LAST PACK_TYPE 0402LF
J 0
(1350 3800);
DISPLAY 0.617021 (1350 3800);
PAINT SKYBLUE (1350 3800);
FORCEPROP 1 LAST TOLERANCE 5%
J 0
(1275 3800);
DISPLAY 0.617021 (1275 3800);
PAINT SKYBLUE (1275 3800);
FORCEPROP 1 LAST VALUE 0
J 2
(1250 3800);
DISPLAY 0.617021 (1250 3800);
PAINT SKYBLUE (1250 3800);
FORCEPROP 1 LAST MATERIAL EMPTY
J 0
(1550 3800);
DISPLAY 0.617021 (1550 3800);
PAINT RED (1550 3800);
FORCEPROP 1 LAST LOCATION PR260
J 0
(900 3800);
DISPLAY 0.617021 (900 3800);
PAINT AQUA (900 3800);
FORCEPROP 1 LASTPIN (1000 3800) $PN 1
J 0
(1012 3812);
DISPLAY 0.617021 (1012 3812);
PAINT MONO (1012 3812);
FORCEPROP 1 LASTPIN (1200 3800) $PN 2
J 0
(1162 3812);
DISPLAY 0.617021 (1162 3812);
PAINT MONO (1162 3812);
FORCEPROP 2 LAST CDS_LIB pure_quanta
J 0
(1100 3800);
DISPLAY INVISIBLE (1100 3800);
FORCEPROP 1 LAST WATTAGE 1/16W
J 2
(1475 3700);
DISPLAY 0.510638 (1475 3700);
PAINT SKYBLUE (1475 3700);
DISPLAY INVISIBLE (1475 3700);
FORCEPROP 1 LAST PATH I22
J 0
(1050 3950);
DISPLAY 0.978723 (1050 3950);
PAINT WHITE (1050 3950);
DISPLAY INVISIBLE (1050 3950);
FORCEPROP 1 LAST LOCATION PR260
J 0
(1050 3900);
DISPLAY 1.021277 (1050 3900);
PAINT AQUA (1050 3900);
DISPLAY INVISIBLE (1050 3900);
FORCEPROP 0 LAST $SEC 1
J 0
(1050 3900);
DISPLAY 0.680851 (1050 3900);
PAINT MONO (1050 3900);
DISPLAY INVISIBLE (1050 3900);
FORCEPROP 0 LAST CDS_SEC 1
J 0
(1050 3900);
DISPLAY 1.021277 (1050 3900);
DISPLAY INVISIBLE (1050 3900);
FORCEADD Q_RES..1
(500 4050);
FORCEPROP 1 LAST PART_NUMBER CS32802FB05
J 0
(400 4125);
DISPLAY 0.617021 (400 4125);
PAINT BLUE (400 4125);
DISPLAY INVISIBLE (400 4125);
FORCEPROP 1 LAST VALUE 28K
J 2
(725 4050);
DISPLAY 0.617021 (725 4050);
PAINT SKYBLUE (725 4050);
FORCEPROP 1 LAST TOLERANCE 1%
J 0
(750 4050);
DISPLAY 0.617021 (750 4050);
PAINT SKYBLUE (750 4050);
FORCEPROP 1 LAST PACK_TYPE 0402LF
J 0
(825 4050);
DISPLAY 0.617021 (825 4050);
PAINT SKYBLUE (825 4050);
FORCEPROP 1 LAST WATTAGE 1/16W
J 2
(650 4175);
DISPLAY 0.617021 (650 4175);
PAINT SKYBLUE (650 4175);
FORCEPROP 1 LAST MATERIAL EMPTY
J 0
(350 4175);
DISPLAY 0.617021 (350 4175);
PAINT RED (350 4175);
FORCEPROP 1 LAST LOCATION PR258
J 0
(300 4050);
DISPLAY 0.617021 (300 4050);
PAINT AQUA (300 4050);
FORCEPROP 1 LASTPIN (400 4050) $PN 1
J 0
(412 4062);
DISPLAY 0.617021 (412 4062);
PAINT MONO (412 4062);
FORCEPROP 1 LASTPIN (600 4050) $PN 2
J 0
(562 4062);
DISPLAY 0.617021 (562 4062);
PAINT MONO (562 4062);
FORCEPROP 2 LAST CDS_LIB pure_quanta
J 0
(500 4050);
DISPLAY INVISIBLE (500 4050);
FORCEPROP 1 LAST PATH I23
J 0
(450 4200);
DISPLAY 0.978723 (450 4200);
PAINT WHITE (450 4200);
DISPLAY INVISIBLE (450 4200);
FORCEPROP 1 LAST LOCATION PR258
J 0
(425 4175);
DISPLAY 1.021277 (425 4175);
PAINT AQUA (425 4175);
DISPLAY INVISIBLE (425 4175);
FORCEPROP 0 LAST $SEC 1
J 0
(425 4175);
DISPLAY 0.680851 (425 4175);
PAINT MONO (425 4175);
DISPLAY INVISIBLE (425 4175);
FORCEPROP 0 LAST CDS_SEC 1
J 0
(425 4175);
DISPLAY 1.021277 (425 4175);
DISPLAY INVISIBLE (425 4175);
FORCEADD VCC15..1
(825 3925);
FORCEPROP 3 LASTPIN (825 3875) SIG_NAME P12V_AUX\g
J 0
(835 3885);
DISPLAY 0.659574 (835 3885);
PAINT MONO (835 3885);
DISPLAY INVISIBLE (835 3885);
FORCEPROP 1 LAST HDL_POWER P12V_AUX
J 1
(825 3975);
DISPLAY 0.617021 (825 3975);
PAINT GREEN (825 3975);
FORCEPROP 2 LAST CDS_LIB logical_power
J 0
(825 3925);
DISPLAY INVISIBLE (825 3925);
FORCEPROP 1 LAST PATH I24
J 0
(875 3950);
DISPLAY 0.872340 (875 3950);
PAINT AQUA (875 3950);
DISPLAY INVISIBLE (875 3950);
FORCEADD VCC15..1
(875 4600);
FORCEPROP 3 LASTPIN (875 4550) SIG_NAME P3V3_AUX\g
J 0
(885 4560);
DISPLAY 0.659574 (885 4560);
PAINT MONO (885 4560);
DISPLAY INVISIBLE (885 4560);
FORCEPROP 1 LAST HDL_POWER P3V3_AUX
J 1
(875 4650);
DISPLAY 0.617021 (875 4650);
PAINT GREEN (875 4650);
FORCEPROP 2 LAST CDS_LIB logical_power
J 0
(875 4600);
PAINT MONO (875 4600);
DISPLAY INVISIBLE (875 4600);
FORCEPROP 1 LAST PATH I25
J 0
(925 4625);
DISPLAY 0.872340 (925 4625);
PAINT AQUA (925 4625);
DISPLAY INVISIBLE (925 4625);
FORCEADD Q_RES..2
(1550 3500);
FORCEPROP 1 LAST PART_NUMBER CS00002JB13
J 0
(1590 3375);
DISPLAY 0.617021 (1590 3375);
PAINT BLUE (1590 3375);
DISPLAY INVISIBLE (1590 3375);
FORCEPROP 1 LAST MATERIAL CHIP
J 0
(1590 3425);
DISPLAY 0.617021 (1590 3425);
PAINT SKYBLUE (1590 3425);
FORCEPROP 1 LAST WATTAGE 1/16W
J 0
(1590 3475);
DISPLAY 0.617021 (1590 3475);
PAINT SKYBLUE (1590 3475);
FORCEPROP 1 LAST TOLERANCE 5%
J 0
(1595 3525);
DISPLAY 0.617021 (1595 3525);
PAINT SKYBLUE (1595 3525);
FORCEPROP 1 LAST PACK_TYPE 0402LF
J 0
(1590 3325);
DISPLAY 0.617021 (1590 3325);
PAINT SKYBLUE (1590 3325);
FORCEPROP 1 LAST VALUE 0
J 0
(1595 3575);
DISPLAY 0.617021 (1595 3575);
PAINT SKYBLUE (1595 3575);
FORCEPROP 1 LAST LOCATION PR275
J 0
(1595 3625);
DISPLAY 0.617021 (1595 3625);
PAINT AQUA (1595 3625);
FORCEPROP 1 LASTPIN (1550 3600) $PN 1
J 0
(1555 3562);
DISPLAY 0.617021 (1555 3562);
PAINT MONO (1555 3562);
FORCEPROP 1 LASTPIN (1550 3400) $PN 2
J 0
(1555 3410);
DISPLAY 0.617021 (1555 3410);
PAINT MONO (1555 3410);
FORCEPROP 2 LAST CDS_LIB pure_quanta
J 0
(1550 3500);
DISPLAY INVISIBLE (1550 3500);
FORCEPROP 1 LAST PATH I26
J 0
(1600 3675);
DISPLAY 0.978723 (1600 3675);
PAINT WHITE (1600 3675);
DISPLAY INVISIBLE (1600 3675);
FORCEPROP 1 LAST LOCATION PR275
J 0
(1600 3675);
DISPLAY 1.021277 (1600 3675);
PAINT AQUA (1600 3675);
DISPLAY INVISIBLE (1600 3675);
FORCEPROP 0 LAST $SEC 1
J 0
(1600 3675);
DISPLAY 0.680851 (1600 3675);
PAINT MONO (1600 3675);
DISPLAY INVISIBLE (1600 3675);
FORCEPROP 0 LAST CDS_SEC 1
J 0
(1600 3675);
DISPLAY 1.021277 (1600 3675);
DISPLAY INVISIBLE (1600 3675);
FORCEADD UNIVERSAL_GND..1
(1875 3200);
FORCEPROP 3 LASTPIN (1875 3250) SIG_NAME GND\g
J 0
(1885 3260);
DISPLAY 0.659574 (1885 3260);
PAINT MONO (1885 3260);
DISPLAY INVISIBLE (1885 3260);
FORCEPROP 1 LAST HDL_POWER GND
J 1
(1900 3125);
DISPLAY 0.872340 (1900 3125);
PAINT GREEN (1900 3125);
DISPLAY INVISIBLE (1900 3125);
FORCEPROP 2 LAST CDS_LIB logical_power
J 0
(1875 3200);
PAINT MONO (1875 3200);
DISPLAY INVISIBLE (1875 3200);
FORCEPROP 1 LAST PATH I27
J 0
(1950 3200);
DISPLAY 0.872340 (1950 3200);
PAINT AQUA (1950 3200);
DISPLAY INVISIBLE (1950 3200);
FORCEADD Q_CAP..1
(1875 3500);
FORCEPROP 1 LAST PART_NUMBER CH4104K1B00
J 0
(1925 3325);
DISPLAY 0.617021 (1925 3325);
PAINT BLUE (1925 3325);
DISPLAY INVISIBLE (1925 3325);
FORCEPROP 1 LAST MATERIAL EMPTY
J 0
(1925 3425);
DISPLAY 0.617021 (1925 3425);
PAINT RED (1925 3425);
FORCEPROP 1 LAST TOLERANCE 10%
J 0
(1925 3475);
DISPLAY 0.617021 (1925 3475);
PAINT SKYBLUE (1925 3475);
FORCEPROP 1 LAST VOLTAGE 25V
J 0
(1925 3525);
DISPLAY 0.617021 (1925 3525);
PAINT SKYBLUE (1925 3525);
FORCEPROP 1 LAST PACK_TYPE 0402
J 0
(1925 3375);
DISPLAY 0.617021 (1925 3375);
PAINT SKYBLUE (1925 3375);
FORCEPROP 1 LAST VALUE 0.1UF
J 0
(1925 3575);
DISPLAY 0.617021 (1925 3575);
PAINT SKYBLUE (1925 3575);
FORCEPROP 1 LAST LOCATION PC467
J 0
(1925 3625);
DISPLAY 0.617021 (1925 3625);
PAINT AQUA (1925 3625);
FORCEPROP 1 LASTPIN (1875 3600) $PN 1
J 0
(1885 3580);
DISPLAY 0.617021 (1885 3580);
PAINT MONO (1885 3580);
FORCEPROP 1 LASTPIN (1875 3400) $PN 2
J 0
(1885 3380);
DISPLAY 0.617021 (1885 3380);
PAINT MONO (1885 3380);
FORCEPROP 2 LAST CDS_LIB pure_quanta
J 0
(1875 3500);
DISPLAY INVISIBLE (1875 3500);
FORCEPROP 1 LAST PATH I28
J 0
(1925 3650);
DISPLAY 0.978723 (1925 3650);
PAINT WHITE (1925 3650);
DISPLAY INVISIBLE (1925 3650);
FORCEPROP 1 LAST LOCATION PC467
J 0
(1925 3675);
DISPLAY 1.021277 (1925 3675);
PAINT AQUA (1925 3675);
DISPLAY INVISIBLE (1925 3675);
FORCEPROP 0 LAST $SEC 1
J 0
(1925 3675);
DISPLAY 0.680851 (1925 3675);
PAINT MONO (1925 3675);
DISPLAY INVISIBLE (1925 3675);
FORCEPROP 0 LAST CDS_SEC 1
J 0
(1925 3675);
DISPLAY 1.021277 (1925 3675);
DISPLAY INVISIBLE (1925 3675);
FORCEADD Q_RES..1
(1350 4350);
FORCEPROP 1 LAST PART_NUMBER CS00002JB13
J 0
(1475 4400);
DISPLAY 0.617021 (1475 4400);
PAINT BLUE (1475 4400);
DISPLAY INVISIBLE (1475 4400);
FORCEPROP 1 LAST VALUE 0
J 2
(1500 4350);
DISPLAY 0.617021 (1500 4350);
PAINT SKYBLUE (1500 4350);
FORCEPROP 1 LAST MATERIAL CHIP
J 0
(1475 4450);
DISPLAY 0.617021 (1475 4450);
PAINT SKYBLUE (1475 4450);
FORCEPROP 1 LAST WATTAGE 1/16W
J 2
(1775 4450);
DISPLAY 0.617021 (1775 4450);
PAINT SKYBLUE (1775 4450);
FORCEPROP 1 LAST PACK_TYPE 0402LF
J 0
(1600 4350);
DISPLAY 0.617021 (1600 4350);
PAINT SKYBLUE (1600 4350);
FORCEPROP 1 LAST TOLERANCE 5%
J 0
(1525 4350);
DISPLAY 0.617021 (1525 4350);
PAINT SKYBLUE (1525 4350);
FORCEPROP 1 LAST LOCATION R2572
J 0
(1125 4350);
DISPLAY 0.617021 (1125 4350);
PAINT AQUA (1125 4350);
FORCEPROP 1 LASTPIN (1250 4350) $PN 1
J 0
(1262 4362);
DISPLAY 0.617021 (1262 4362);
PAINT MONO (1262 4362);
FORCEPROP 1 LASTPIN (1450 4350) $PN 2
J 0
(1412 4362);
DISPLAY 0.617021 (1412 4362);
PAINT MONO (1412 4362);
FORCEPROP 2 LAST CDS_LIB pure_quanta
J 0
(1350 4350);
DISPLAY INVISIBLE (1350 4350);
FORCEPROP 1 LAST PATH I29
J 0
(1300 4500);
DISPLAY 0.978723 (1300 4500);
PAINT WHITE (1300 4500);
DISPLAY INVISIBLE (1300 4500);
FORCEPROP 1 LAST LOCATION R2572
J 0
(1300 4450);
DISPLAY 1.021277 (1300 4450);
PAINT AQUA (1300 4450);
DISPLAY INVISIBLE (1300 4450);
FORCEPROP 0 LAST $SEC 1
J 0
(1300 4450);
DISPLAY 0.680851 (1300 4450);
PAINT MONO (1300 4450);
DISPLAY INVISIBLE (1300 4450);
FORCEPROP 0 LAST CDS_SEC 1
J 0
(1300 4450);
DISPLAY 1.021277 (1300 4450);
DISPLAY INVISIBLE (1300 4450);
FORCEADD OFFPAGE..1
(225 4750);
FORCEPROP 2 LAST $XR0 222 
J 0
(-27 4750);
DISPLAY 0.638298 (-27 4750);
PAINT MONO (-27 4750);
FORCEPROP 1 LAST COMMENT_BODY TRUE
J 0
(350 4650);
DISPLAY 0.872340 (350 4650);
PAINT GREEN (350 4650);
DISPLAY INVISIBLE (350 4650);
FORCEPROP 1 LAST OFFPAGE TRUE
J 0
(550 4625);
DISPLAY 0.872340 (550 4625);
PAINT GREEN (550 4625);
DISPLAY INVISIBLE (550 4625);
FORCEPROP 2 LAST CDS_LIB standard
J 0
(225 4750);
DISPLAY INVISIBLE (225 4750);
FORCEPROP 2 LAST PATH I3
J 0
(-25 4800);
DISPLAY 1.021277 (-25 4800);
DISPLAY INVISIBLE (-25 4800);
FORCEADD Q_RES..1
(1350 4500);
FORCEPROP 1 LAST PART_NUMBER CS21002FB06
J 0
(1475 4550);
DISPLAY 0.617021 (1475 4550);
PAINT BLUE (1475 4550);
DISPLAY INVISIBLE (1475 4550);
FORCEPROP 1 LAST MATERIAL CHIP
J 0
(1475 4600);
DISPLAY 0.617021 (1475 4600);
PAINT SKYBLUE (1475 4600);
FORCEPROP 1 LAST TOLERANCE 1%
J 0
(1550 4500);
DISPLAY 0.617021 (1550 4500);
PAINT SKYBLUE (1550 4500);
FORCEPROP 1 LAST PACK_TYPE 0402LF
J 0
(1650 4500);
DISPLAY 0.617021 (1650 4500);
PAINT SKYBLUE (1650 4500);
FORCEPROP 1 LAST WATTAGE 1/16W
J 2
(1775 4600);
DISPLAY 0.617021 (1775 4600);
PAINT SKYBLUE (1775 4600);
FORCEPROP 1 LAST VALUE 1K
J 2
(1525 4500);
DISPLAY 0.617021 (1525 4500);
PAINT SKYBLUE (1525 4500);
FORCEPROP 1 LAST LOCATION R2571
J 0
(1125 4500);
DISPLAY 0.617021 (1125 4500);
PAINT AQUA (1125 4500);
FORCEPROP 1 LASTPIN (1250 4500) $PN 1
J 0
(1262 4512);
DISPLAY 0.617021 (1262 4512);
PAINT MONO (1262 4512);
FORCEPROP 1 LASTPIN (1450 4500) $PN 2
J 0
(1412 4512);
DISPLAY 0.617021 (1412 4512);
PAINT MONO (1412 4512);
FORCEPROP 2 LAST CDS_LIB pure_quanta
J 0
(1350 4500);
DISPLAY INVISIBLE (1350 4500);
FORCEPROP 1 LAST PATH I30
J 0
(1300 4650);
DISPLAY 0.978723 (1300 4650);
PAINT WHITE (1300 4650);
DISPLAY INVISIBLE (1300 4650);
FORCEPROP 1 LAST LOCATION R2571
J 0
(1300 4600);
DISPLAY 1.021277 (1300 4600);
PAINT AQUA (1300 4600);
DISPLAY INVISIBLE (1300 4600);
FORCEPROP 0 LAST $SEC 1
J 0
(1300 4600);
DISPLAY 0.680851 (1300 4600);
PAINT MONO (1300 4600);
DISPLAY INVISIBLE (1300 4600);
FORCEPROP 0 LAST CDS_SEC 1
J 0
(1300 4600);
DISPLAY 1.021277 (1300 4600);
DISPLAY INVISIBLE (1300 4600);
FORCEADD Q_RES..1
(1350 4750);
FORCEPROP 1 LAST PART_NUMBER CS00002JB13
J 0
(1475 4800);
DISPLAY 0.617021 (1475 4800);
PAINT BLUE (1475 4800);
DISPLAY INVISIBLE (1475 4800);
FORCEPROP 1 LAST WATTAGE 1/16W
J 2
(1775 4850);
DISPLAY 0.617021 (1775 4850);
PAINT SKYBLUE (1775 4850);
FORCEPROP 1 LAST MATERIAL CHIP
J 0
(1475 4850);
DISPLAY 0.617021 (1475 4850);
PAINT SKYBLUE (1475 4850);
FORCEPROP 1 LAST PACK_TYPE 0402LF
J 0
(1600 4750);
DISPLAY 0.617021 (1600 4750);
PAINT SKYBLUE (1600 4750);
FORCEPROP 1 LAST TOLERANCE 5%
J 0
(1525 4750);
DISPLAY 0.617021 (1525 4750);
PAINT SKYBLUE (1525 4750);
FORCEPROP 1 LAST VALUE 0
J 2
(1500 4750);
DISPLAY 0.617021 (1500 4750);
PAINT SKYBLUE (1500 4750);
FORCEPROP 1 LAST LOCATION R2570
J 0
(1125 4750);
DISPLAY 0.617021 (1125 4750);
PAINT AQUA (1125 4750);
FORCEPROP 1 LASTPIN (1250 4750) $PN 1
J 0
(1262 4762);
DISPLAY 0.617021 (1262 4762);
PAINT MONO (1262 4762);
FORCEPROP 1 LASTPIN (1450 4750) $PN 2
J 0
(1412 4762);
DISPLAY 0.617021 (1412 4762);
PAINT MONO (1412 4762);
FORCEPROP 2 LAST CDS_LIB pure_quanta
J 0
(1350 4750);
DISPLAY INVISIBLE (1350 4750);
FORCEPROP 1 LAST PATH I31
J 0
(1300 4900);
DISPLAY 0.978723 (1300 4900);
PAINT WHITE (1300 4900);
DISPLAY INVISIBLE (1300 4900);
FORCEPROP 1 LAST LOCATION R2570
J 0
(1300 4850);
DISPLAY 1.021277 (1300 4850);
PAINT AQUA (1300 4850);
DISPLAY INVISIBLE (1300 4850);
FORCEPROP 0 LAST $SEC 1
J 0
(1300 4850);
DISPLAY 0.680851 (1300 4850);
PAINT MONO (1300 4850);
DISPLAY INVISIBLE (1300 4850);
FORCEPROP 0 LAST CDS_SEC 1
J 0
(1300 4850);
DISPLAY 1.021277 (1300 4850);
DISPLAY INVISIBLE (1300 4850);
FORCEADD Q_CAP..2
(2150 4500);
FORCEPROP 1 LAST PART_NUMBER TMP_QCH21006JB10
J 1
(2425 4450);
DISPLAY 0.617021 (2425 4450);
PAINT BLUE (2425 4450);
DISPLAY INVISIBLE (2425 4450);
FORCEPROP 1 LAST PACK_TYPE 0402
J 1
(2675 4425);
DISPLAY 0.617021 (2675 4425);
PAINT SKYBLUE (2675 4425);
FORCEPROP 1 LAST TOLERANCE 5%
J 2
(2800 4450);
DISPLAY 0.617021 (2800 4450);
PAINT SKYBLUE (2800 4450);
FORCEPROP 1 LAST VALUE 1000PF
J 2
(2475 4500);
DISPLAY 0.617021 (2475 4500);
PAINT SKYBLUE (2475 4500);
FORCEPROP 1 LAST MATERIAL EMPTY
J 0
(2625 4500);
DISPLAY 0.617021 (2625 4500);
PAINT RED (2625 4500);
FORCEPROP 1 LAST VOLTAGE 50V
J 0
(2500 4500);
DISPLAY 0.617021 (2500 4500);
PAINT SKYBLUE (2500 4500);
FORCEPROP 1 LAST LOCATION C2453
J 1
(1950 4500);
DISPLAY 0.617021 (1950 4500);
PAINT AQUA (1950 4500);
FORCEPROP 1 LASTPIN (2050 4500) $PN 1
J 0
(2040 4515);
DISPLAY 0.617021 (2040 4515);
PAINT MONO (2040 4515);
FORCEPROP 1 LASTPIN (2250 4500) $PN 2
J 0
(2235 4515);
DISPLAY 0.617021 (2235 4515);
PAINT MONO (2235 4515);
FORCEPROP 2 LAST CDS_LIB pure_quanta
J 0
(2150 4500);
DISPLAY INVISIBLE (2150 4500);
FORCEPROP 1 LAST PATH I32
J 0
(2150 4700);
DISPLAY 0.978723 (2150 4700);
PAINT WHITE (2150 4700);
DISPLAY INVISIBLE (2150 4700);
FORCEPROP 1 LAST LOCATION C2453
J 0
(2100 4600);
DISPLAY 1.021277 (2100 4600);
PAINT AQUA (2100 4600);
DISPLAY INVISIBLE (2100 4600);
FORCEPROP 0 LAST $SEC 1
J 0
(2100 4600);
DISPLAY 0.680851 (2100 4600);
PAINT MONO (2100 4600);
DISPLAY INVISIBLE (2100 4600);
FORCEPROP 0 LAST CDS_SEC 1
J 0
(2100 4600);
DISPLAY 1.021277 (2100 4600);
DISPLAY INVISIBLE (2100 4600);
FORCEADD Q_CAP..2
(2150 4625);
FORCEPROP 1 LAST PART_NUMBER TMP_QCH21006JB10
J 1
(2425 4575);
DISPLAY 0.617021 (2425 4575);
PAINT BLUE (2425 4575);
DISPLAY INVISIBLE (2425 4575);
FORCEPROP 1 LAST MATERIAL X7R
J 0
(2625 4625);
DISPLAY 0.617021 (2625 4625);
PAINT SKYBLUE (2625 4625);
FORCEPROP 1 LAST VOLTAGE 50V
J 0
(2500 4625);
DISPLAY 0.617021 (2500 4625);
PAINT SKYBLUE (2500 4625);
FORCEPROP 1 LAST VALUE 1000PF
J 2
(2475 4625);
DISPLAY 0.617021 (2475 4625);
PAINT SKYBLUE (2475 4625);
FORCEPROP 1 LAST TOLERANCE 5%
J 2
(2800 4575);
DISPLAY 0.617021 (2800 4575);
PAINT SKYBLUE (2800 4575);
FORCEPROP 1 LAST PACK_TYPE 0402
J 1
(2675 4550);
DISPLAY 0.617021 (2675 4550);
PAINT SKYBLUE (2675 4550);
FORCEPROP 1 LAST LOCATION C2452
J 1
(1950 4625);
DISPLAY 0.617021 (1950 4625);
PAINT AQUA (1950 4625);
FORCEPROP 1 LASTPIN (2050 4625) $PN 1
J 0
(2040 4640);
DISPLAY 0.617021 (2040 4640);
PAINT MONO (2040 4640);
FORCEPROP 1 LASTPIN (2250 4625) $PN 2
J 0
(2235 4640);
DISPLAY 0.617021 (2235 4640);
PAINT MONO (2235 4640);
FORCEPROP 2 LAST CDS_LIB pure_quanta
J 0
(2150 4625);
DISPLAY INVISIBLE (2150 4625);
FORCEPROP 1 LAST PATH I33
J 0
(2150 4825);
DISPLAY 0.978723 (2150 4825);
PAINT WHITE (2150 4825);
DISPLAY INVISIBLE (2150 4825);
FORCEPROP 1 LAST LOCATION C2452
J 0
(2100 4725);
DISPLAY 1.021277 (2100 4725);
PAINT AQUA (2100 4725);
DISPLAY INVISIBLE (2100 4725);
FORCEPROP 0 LAST $SEC 1
J 0
(2100 4725);
DISPLAY 0.680851 (2100 4725);
PAINT MONO (2100 4725);
DISPLAY INVISIBLE (2100 4725);
FORCEPROP 0 LAST CDS_SEC 1
J 0
(2100 4725);
DISPLAY 1.021277 (2100 4725);
DISPLAY INVISIBLE (2100 4725);
FORCEADD UNIVERSAL_GND..1
(2625 3200);
FORCEPROP 3 LASTPIN (2625 3250) SIG_NAME GND\g
J 0
(2635 3260);
DISPLAY 0.659574 (2635 3260);
PAINT MONO (2635 3260);
DISPLAY INVISIBLE (2635 3260);
FORCEPROP 1 LAST HDL_POWER GND
J 1
(2650 3125);
DISPLAY 0.872340 (2650 3125);
PAINT GREEN (2650 3125);
DISPLAY INVISIBLE (2650 3125);
FORCEPROP 2 LAST CDS_LIB logical_power
J 0
(2625 3200);
PAINT MONO (2625 3200);
DISPLAY INVISIBLE (2625 3200);
FORCEPROP 1 LAST PATH I34
J 0
(2700 3200);
DISPLAY 0.872340 (2700 3200);
PAINT AQUA (2700 3200);
DISPLAY INVISIBLE (2700 3200);
FORCEADD Q_RES..2
(2300 3500);
FORCEPROP 1 LAST PART_NUMBER CS21002FB06
J 0
(2340 3375);
DISPLAY 0.617021 (2340 3375);
PAINT BLUE (2340 3375);
DISPLAY INVISIBLE (2340 3375);
FORCEPROP 1 LAST WATTAGE 1/16W
J 0
(2340 3475);
DISPLAY 0.617021 (2340 3475);
PAINT SKYBLUE (2340 3475);
FORCEPROP 1 LAST MATERIAL EMPTY
J 0
(2340 3425);
DISPLAY 0.617021 (2340 3425);
PAINT RED (2340 3425);
FORCEPROP 1 LAST TOLERANCE 1%
J 0
(2345 3525);
DISPLAY 0.617021 (2345 3525);
PAINT SKYBLUE (2345 3525);
FORCEPROP 1 LAST VALUE 1K
J 0
(2345 3575);
DISPLAY 0.617021 (2345 3575);
PAINT SKYBLUE (2345 3575);
FORCEPROP 1 LAST PACK_TYPE 0402LF
J 0
(2340 3325);
DISPLAY 0.617021 (2340 3325);
PAINT SKYBLUE (2340 3325);
FORCEPROP 1 LAST LOCATION PR276
J 0
(2345 3625);
DISPLAY 0.617021 (2345 3625);
PAINT AQUA (2345 3625);
FORCEPROP 1 LASTPIN (2300 3600) $PN 1
J 0
(2305 3562);
DISPLAY 0.617021 (2305 3562);
PAINT MONO (2305 3562);
FORCEPROP 1 LASTPIN (2300 3400) $PN 2
J 0
(2305 3410);
DISPLAY 0.617021 (2305 3410);
PAINT MONO (2305 3410);
FORCEPROP 2 LAST CDS_LIB pure_quanta
J 0
(2300 3500);
DISPLAY INVISIBLE (2300 3500);
FORCEPROP 1 LAST PATH I35
J 0
(2350 3675);
DISPLAY 0.978723 (2350 3675);
PAINT WHITE (2350 3675);
DISPLAY INVISIBLE (2350 3675);
FORCEPROP 1 LAST LOCATION PR276
J 0
(2350 3675);
DISPLAY 1.021277 (2350 3675);
PAINT AQUA (2350 3675);
DISPLAY INVISIBLE (2350 3675);
FORCEPROP 0 LAST $SEC 1
J 0
(2350 3675);
DISPLAY 0.680851 (2350 3675);
PAINT MONO (2350 3675);
DISPLAY INVISIBLE (2350 3675);
FORCEPROP 0 LAST CDS_SEC 1
J 0
(2350 3675);
DISPLAY 1.021277 (2350 3675);
DISPLAY INVISIBLE (2350 3675);
FORCEADD Q_CAP..1
(2625 3500);
FORCEPROP 1 LAST PART_NUMBER CH4104K1B00
J 0
(2675 3325);
DISPLAY 0.617021 (2675 3325);
PAINT BLUE (2675 3325);
DISPLAY INVISIBLE (2675 3325);
FORCEPROP 1 LAST VOLTAGE 25V
J 0
(2675 3525);
DISPLAY 0.617021 (2675 3525);
PAINT SKYBLUE (2675 3525);
FORCEPROP 1 LAST TOLERANCE 10%
J 0
(2675 3475);
DISPLAY 0.617021 (2675 3475);
PAINT SKYBLUE (2675 3475);
FORCEPROP 1 LAST VALUE 0.1UF
J 0
(2675 3575);
DISPLAY 0.617021 (2675 3575);
PAINT SKYBLUE (2675 3575);
FORCEPROP 1 LAST PACK_TYPE 0402
J 0
(2675 3375);
DISPLAY 0.617021 (2675 3375);
PAINT SKYBLUE (2675 3375);
FORCEPROP 1 LAST MATERIAL X7R
J 0
(2675 3425);
DISPLAY 0.617021 (2675 3425);
PAINT SKYBLUE (2675 3425);
FORCEPROP 1 LAST LOCATION PC474
J 0
(2675 3625);
DISPLAY 0.617021 (2675 3625);
PAINT AQUA (2675 3625);
FORCEPROP 1 LASTPIN (2625 3600) $PN 1
J 0
(2635 3580);
DISPLAY 0.617021 (2635 3580);
PAINT MONO (2635 3580);
FORCEPROP 1 LASTPIN (2625 3400) $PN 2
J 0
(2635 3380);
DISPLAY 0.617021 (2635 3380);
PAINT MONO (2635 3380);
FORCEPROP 2 LAST CDS_LIB pure_quanta
J 0
(2625 3500);
DISPLAY INVISIBLE (2625 3500);
FORCEPROP 1 LAST PATH I36
J 0
(2675 3650);
DISPLAY 0.978723 (2675 3650);
PAINT WHITE (2675 3650);
DISPLAY INVISIBLE (2675 3650);
FORCEPROP 1 LAST LOCATION PC474
J 0
(2675 3675);
DISPLAY 1.021277 (2675 3675);
PAINT AQUA (2675 3675);
DISPLAY INVISIBLE (2675 3675);
FORCEPROP 0 LAST $SEC 1
J 0
(2675 3675);
DISPLAY 0.680851 (2675 3675);
PAINT MONO (2675 3675);
DISPLAY INVISIBLE (2675 3675);
FORCEPROP 0 LAST CDS_SEC 1
J 0
(2675 3675);
DISPLAY 1.021277 (2675 3675);
DISPLAY INVISIBLE (2675 3675);
FORCEADD UNIVERSAL_GND..1
(2800 3475);
FORCEPROP 3 LASTPIN (2800 3525) SIG_NAME GND\g
J 0
(2810 3535);
DISPLAY 0.659574 (2810 3535);
PAINT MONO (2810 3535);
DISPLAY INVISIBLE (2810 3535);
FORCEPROP 1 LAST HDL_POWER GND
J 1
(2825 3400);
DISPLAY 0.872340 (2825 3400);
PAINT GREEN (2825 3400);
DISPLAY INVISIBLE (2825 3400);
FORCEPROP 2 LAST CDS_LIB logical_power
J 0
(2800 3475);
PAINT MONO (2800 3475);
DISPLAY INVISIBLE (2800 3475);
FORCEPROP 1 LAST PATH I37
J 0
(2875 3475);
DISPLAY 0.872340 (2875 3475);
PAINT AQUA (2875 3475);
DISPLAY INVISIBLE (2875 3475);
FORCEADD ISL69260IRAZT..1
(3550 6400);
FORCEPROP 1 LAST PART_NUMBER AL069260000
J 0
(3005 9345);
DISPLAY 0.617021 (3005 9345);
PAINT BLUE (3005 9345);
DISPLAY INVISIBLE (3005 9345);
FORCEPROP 2 LAST VALUE ISL69260IRAZ-T
J 0
(3525 9350);
DISPLAY 0.617021 (3525 9350);
PAINT SKYBLUE (3525 9350);
FORCEPROP 1 LAST MATERIAL IC
J 0
(3005 9258);
DISPLAY 0.617021 (3005 9258);
PAINT SKYBLUE (3005 9258);
FORCEPROP 2 LAST PART_TYPE SMLF
J 0
(3525 9400);
DISPLAY 0.638298 (3525 9400);
FORCEPROP 1 LAST LOCATION PU22
J 0
(3005 9452);
DISPLAY 0.617021 (3005 9452);
PAINT AQUA (3005 9452);
FORCEPROP 0 LASTPIN (2875 4050) $PN 34
J 2
(2865 4060);
DISPLAY 0.680851 (2865 4060);
PAINT MONO (2865 4060);
FORCEPROP 0 LASTPIN (2875 5150) $PN 33
J 2
(2865 5160);
DISPLAY 0.680851 (2865 5160);
PAINT MONO (2865 5160);
FORCEPROP 0 LASTPIN (4225 4900) $PN 30
J 0
(4235 4910);
DISPLAY 0.680851 (4235 4910);
PAINT MONO (4235 4910);
FORCEPROP 0 LASTPIN (4225 5350) $PN 29
J 0
(4235 5360);
DISPLAY 0.680851 (4235 5360);
PAINT MONO (4235 5360);
FORCEPROP 0 LASTPIN (4225 5800) $PN 28
J 0
(4235 5810);
DISPLAY 0.680851 (4235 5810);
PAINT MONO (4235 5810);
FORCEPROP 0 LASTPIN (4225 6250) $PN 27
J 0
(4235 6260);
DISPLAY 0.680851 (4235 6260);
PAINT MONO (4235 6260);
FORCEPROP 0 LASTPIN (4225 6700) $PN 26
J 0
(4235 6710);
DISPLAY 0.680851 (4235 6710);
PAINT MONO (4235 6710);
FORCEPROP 0 LASTPIN (4225 7150) $PN 25
J 0
(4235 7160);
DISPLAY 0.680851 (4235 7160);
PAINT MONO (4235 7160);
FORCEPROP 0 LASTPIN (4225 7600) $PN 24
J 0
(4235 7610);
DISPLAY 0.680851 (4235 7610);
PAINT MONO (4235 7610);
FORCEPROP 0 LASTPIN (4225 8050) $PN 23
J 0
(4235 8060);
DISPLAY 0.680851 (4235 8060);
PAINT MONO (4235 8060);
FORCEPROP 0 LASTPIN (2875 9000) $PN 13
J 2
(2865 9010);
DISPLAY 0.680851 (2865 9010);
PAINT MONO (2865 9010);
FORCEPROP 0 LASTPIN (2875 4750) $PN 20
J 2
(2865 4760);
DISPLAY 0.680851 (2865 4760);
PAINT MONO (2865 4760);
FORCEPROP 0 LASTPIN (2875 9150) $PN 12
J 2
(2865 9160);
DISPLAY 0.680851 (2865 9160);
PAINT MONO (2865 9160);
FORCEPROP 0 LASTPIN (2875 4350) $PN 16
J 2
(2865 4360);
DISPLAY 0.680851 (2865 4360);
PAINT MONO (2865 4360);
FORCEPROP 0 LASTPIN (2875 8000) $PN 10
J 2
(2865 8010);
DISPLAY 0.680851 (2865 8010);
PAINT MONO (2865 8010);
FORCEPROP 0 LASTPIN (2875 7850) $PN 9
J 2
(2865 7860);
DISPLAY 0.680851 (2865 7860);
PAINT MONO (2865 7860);
FORCEPROP 0 LASTPIN (4225 5000) $PN 1
J 0
(4235 5010);
DISPLAY 0.680851 (4235 5010);
PAINT MONO (4235 5010);
FORCEPROP 0 LASTPIN (4225 5450) $PN 2
J 0
(4235 5460);
DISPLAY 0.680851 (4235 5460);
PAINT MONO (4235 5460);
FORCEPROP 0 LASTPIN (4225 5900) $PN 3
J 0
(4235 5910);
DISPLAY 0.680851 (4235 5910);
PAINT MONO (4235 5910);
FORCEPROP 0 LASTPIN (4225 6350) $PN 4
J 0
(4235 6360);
DISPLAY 0.680851 (4235 6360);
PAINT MONO (4235 6360);
FORCEPROP 0 LASTPIN (4225 6800) $PN 5
J 0
(4235 6810);
DISPLAY 0.680851 (4235 6810);
PAINT MONO (4235 6810);
FORCEPROP 0 LASTPIN (4225 7250) $PN 6
J 0
(4235 7260);
DISPLAY 0.680851 (4235 7260);
PAINT MONO (4235 7260);
FORCEPROP 0 LASTPIN (4225 7700) $PN 7
J 0
(4235 7710);
DISPLAY 0.680851 (4235 7710);
PAINT MONO (4235 7710);
FORCEPROP 0 LASTPIN (4225 8150) $PN 8
J 0
(4235 8160);
DISPLAY 0.680851 (4235 8160);
PAINT MONO (4235 8160);
FORCEPROP 0 LASTPIN (2875 6850) $PN 22
J 2
(2865 6860);
DISPLAY 0.680851 (2865 6860);
PAINT MONO (2865 6860);
FORCEPROP 0 LASTPIN (2875 5750) $PN 31
J 2
(2865 5760);
DISPLAY 0.680851 (2865 5760);
PAINT MONO (2865 5760);
FORCEPROP 0 LASTPIN (2875 8700) $PN 17
J 2
(2865 8710);
DISPLAY 0.680851 (2865 8710);
PAINT MONO (2865 8710);
FORCEPROP 0 LASTPIN (2875 8550) $PN 18
J 2
(2865 8560);
DISPLAY 0.680851 (2865 8560);
PAINT MONO (2865 8560);
FORCEPROP 0 LASTPIN (4225 3950) $PN 35
J 0
(4235 3960);
DISPLAY 0.680851 (4235 3960);
PAINT MONO (4235 3960);
FORCEPROP 0 LASTPIN (4225 4250) $PN 36
J 0
(4235 4260);
DISPLAY 0.680851 (4235 4260);
PAINT MONO (4235 4260);
FORCEPROP 0 LASTPIN (2875 3600) $PN TH
J 2
(2865 3610);
DISPLAY 0.680851 (2865 3610);
PAINT MONO (2865 3610);
FORCEPROP 0 LASTPIN (4225 9150) $PN 39
J 0
(4235 9160);
DISPLAY 0.680851 (4235 9160);
PAINT MONO (4235 9160);
FORCEPROP 0 LASTPIN (4225 8850) $PN 40
J 0
(4235 8860);
DISPLAY 0.680851 (4235 8860);
PAINT MONO (4235 8860);
FORCEPROP 0 LASTPIN (2875 7100) $PN 21
J 2
(2865 7110);
DISPLAY 0.680851 (2865 7110);
PAINT MONO (2865 7110);
FORCEPROP 0 LASTPIN (2875 6000) $PN 32
J 2
(2865 6010);
DISPLAY 0.680851 (2865 6010);
PAINT MONO (2865 6010);
FORCEPROP 0 LASTPIN (2875 4900) $PN 15
J 2
(2865 4910);
DISPLAY 0.680851 (2865 4910);
PAINT MONO (2865 4910);
FORCEPROP 0 LASTPIN (2875 7700) $PN 11
J 2
(2865 7710);
DISPLAY 0.680851 (2865 7710);
PAINT MONO (2865 7710);
FORCEPROP 0 LASTPIN (2875 8400) $PN 19
J 2
(2865 8410);
DISPLAY 0.680851 (2865 8410);
PAINT MONO (2865 8410);
FORCEPROP 0 LASTPIN (4225 4650) $PN 14
J 0
(4235 4660);
DISPLAY 0.680851 (4235 4660);
PAINT MONO (4235 4660);
FORCEPROP 0 LASTPIN (2875 3700) $PN 38
J 2
(2865 3710);
DISPLAY 0.680851 (2865 3710);
PAINT MONO (2865 3710);
FORCEPROP 0 LASTPIN (2875 3800) $PN 37
J 2
(2865 3810);
DISPLAY 0.680851 (2865 3810);
PAINT MONO (2865 3810);
FORCEPROP 1 LAST PATH I38
J 0
(3550 6400);
DISPLAY 0.723404 (3550 6400);
PAINT GREEN (3550 6400);
DISPLAY INVISIBLE (3550 6400);
FORCEPROP 1 LAST NEEDS_NO_SIZE TRUE
J 0
(3550 6400);
DISPLAY 0.723404 (3550 6400);
PAINT GREEN (3550 6400);
DISPLAY INVISIBLE (3550 6400);
FORCEPROP 1 LAST CDS_LMAN_SYM_OUTLINE -550,2850,500,-2850
J 0
(3550 6400);
DISPLAY 0.468085 (3550 6400);
PAINT GREEN (3550 6400);
DISPLAY INVISIBLE (3550 6400);
FORCEPROP 2 LAST CDS_LIB pure_quanta
J 0
(3550 6400);
DISPLAY INVISIBLE (3550 6400);
FORCEPROP 0 LAST $SEC 1
J 0
(3025 9500);
DISPLAY 0.680851 (3025 9500);
PAINT MONO (3025 9500);
DISPLAY INVISIBLE (3025 9500);
FORCEPROP 0 LAST CDS_SEC 1
J 0
(3050 9475);
DISPLAY 1.021277 (3050 9475);
DISPLAY INVISIBLE (3050 9475);
FORCEADD UNIVERSAL_GND..1
R 1
(2850 4500);
FORCEPROP 3 LASTPIN (2800 4500) SIG_NAME GND\g
J 0
(2810 4510);
DISPLAY 0.659574 (2810 4510);
PAINT MONO (2810 4510);
DISPLAY INVISIBLE (2810 4510);
FORCEPROP 1 LAST HDL_POWER GND
R 1
J 1
(2925 4525);
DISPLAY 0.872340 (2925 4525);
PAINT GREEN (2925 4525);
DISPLAY INVISIBLE (2925 4525);
FORCEPROP 2 LAST CDS_LIB logical_power
J 0
(2850 4500);
PAINT MONO (2850 4500);
DISPLAY INVISIBLE (2850 4500);
FORCEPROP 1 LAST PATH I39
R 1
J 0
(2850 4575);
DISPLAY 0.872340 (2850 4575);
PAINT AQUA (2850 4575);
DISPLAY INVISIBLE (2850 4575);
FORCEADD OFFPAGE..1
(-725 5675);
FORCEPROP 2 LAST $XR0 47 
J 0
(-1006 5675);
DISPLAY 0.638298 (-1006 5675);
PAINT MONO (-1006 5675);
FORCEPROP 1 LAST COMMENT_BODY TRUE
J 0
(-600 5575);
DISPLAY 0.872340 (-600 5575);
PAINT GREEN (-600 5575);
DISPLAY INVISIBLE (-600 5575);
FORCEPROP 1 LAST OFFPAGE TRUE
J 0
(-400 5550);
DISPLAY 0.872340 (-400 5550);
PAINT GREEN (-400 5550);
DISPLAY INVISIBLE (-400 5550);
FORCEPROP 2 LAST CDS_LIB standard
J 0
(-725 5675);
DISPLAY INVISIBLE (-725 5675);
FORCEPROP 2 LAST PATH I4
J 0
(-1000 5725);
DISPLAY 1.021277 (-1000 5725);
DISPLAY INVISIBLE (-1000 5725);
FORCEADD UNIVERSAL_GND..1
R 1
(2850 4625);
FORCEPROP 3 LASTPIN (2800 4625) SIG_NAME GND\g
J 0
(2810 4635);
DISPLAY 0.659574 (2810 4635);
PAINT MONO (2810 4635);
DISPLAY INVISIBLE (2810 4635);
FORCEPROP 1 LAST HDL_POWER GND
R 1
J 1
(2925 4650);
DISPLAY 0.872340 (2925 4650);
PAINT GREEN (2925 4650);
DISPLAY INVISIBLE (2925 4650);
FORCEPROP 2 LAST CDS_LIB logical_power
J 0
(2850 4625);
PAINT MONO (2850 4625);
DISPLAY INVISIBLE (2850 4625);
FORCEPROP 1 LAST PATH I40
R 1
J 0
(2850 4700);
DISPLAY 0.872340 (2850 4700);
PAINT AQUA (2850 4700);
DISPLAY INVISIBLE (2850 4700);
FORCEADD Q_RES..1
(550 5525);
FORCEPROP 1 LAST PART_NUMBER CS11002FB07
J 0
(675 5575);
DISPLAY 0.617021 (675 5575);
PAINT BLUE (675 5575);
DISPLAY INVISIBLE (675 5575);
FORCEPROP 1 LAST MATERIAL CHIP
J 0
(675 5625);
DISPLAY 0.617021 (675 5625);
PAINT SKYBLUE (675 5625);
FORCEPROP 1 LAST TOLERANCE 1%
J 0
(775 5525);
DISPLAY 0.617021 (775 5525);
PAINT SKYBLUE (775 5525);
FORCEPROP 1 LAST VALUE 100
J 2
(750 5525);
DISPLAY 0.617021 (750 5525);
PAINT SKYBLUE (750 5525);
FORCEPROP 1 LAST PACK_TYPE 0402LF
J 0
(850 5525);
DISPLAY 0.617021 (850 5525);
PAINT SKYBLUE (850 5525);
FORCEPROP 1 LAST WATTAGE 1/16W
J 2
(975 5625);
DISPLAY 0.617021 (975 5625);
PAINT SKYBLUE (975 5625);
FORCEPROP 1 LAST LOCATION PR567
J 0
(325 5525);
DISPLAY 0.617021 (325 5525);
PAINT AQUA (325 5525);
FORCEPROP 1 LASTPIN (450 5525) $PN 1
J 0
(462 5537);
DISPLAY 0.617021 (462 5537);
FORCEPROP 1 LASTPIN (650 5525) $PN 2
J 0
(612 5537);
DISPLAY 0.617021 (612 5537);
FORCEPROP 2 LAST CDS_LIB pure_quanta
J 0
(550 5525);
PAINT MONO (550 5525);
DISPLAY INVISIBLE (550 5525);
FORCEPROP 1 LAST PATH I41
J 0
(500 5675);
DISPLAY 0.978723 (500 5675);
PAINT WHITE (500 5675);
DISPLAY INVISIBLE (500 5675);
FORCEPROP 2 LAST $SEC 1
J 0
(500 5725);
DISPLAY 0.680851 (500 5725);
PAINT MONO (500 5725);
DISPLAY INVISIBLE (500 5725);
FORCEPROP 2 LAST CDS_SEC 1
J 0
(500 5725);
DISPLAY 1.021277 (500 5725);
DISPLAY INVISIBLE (500 5725);
FORCEADD VCC15..1
(1025 5275);
FORCEPROP 3 LASTPIN (1025 5225) SIG_NAME P3V3_AUX\g
J 0
(1035 5235);
DISPLAY 0.659574 (1035 5235);
PAINT MONO (1035 5235);
DISPLAY INVISIBLE (1035 5235);
FORCEPROP 1 LAST HDL_POWER P3V3_AUX
J 1
(1025 5325);
DISPLAY 0.617021 (1025 5325);
PAINT GREEN (1025 5325);
FORCEPROP 2 LAST CDS_LIB logical_power
J 0
(1025 5275);
DISPLAY INVISIBLE (1025 5275);
FORCEPROP 1 LAST PATH I42
J 0
(1075 5300);
DISPLAY 0.872340 (1075 5300);
PAINT AQUA (1075 5300);
DISPLAY INVISIBLE (1075 5300);
FORCEADD UNIVERSAL_GND..1
(1025 5425);
FORCEPROP 3 LASTPIN (1025 5475) SIG_NAME GND\g
J 0
(1035 5485);
DISPLAY 0.659574 (1035 5485);
PAINT MONO (1035 5485);
DISPLAY INVISIBLE (1035 5485);
FORCEPROP 1 LAST HDL_POWER GND
J 1
(1050 5350);
DISPLAY 0.872340 (1050 5350);
PAINT GREEN (1050 5350);
DISPLAY INVISIBLE (1050 5350);
FORCEPROP 2 LAST CDS_LIB logical_power
J 0
(1025 5425);
PAINT MONO (1025 5425);
DISPLAY INVISIBLE (1025 5425);
FORCEPROP 1 LAST PATH I43
J 0
(1100 5425);
DISPLAY 0.872340 (1100 5425);
PAINT AQUA (1100 5425);
DISPLAY INVISIBLE (1100 5425);
FORCEADD Q_SHORT..1
(475 6050);
FORCEPROP 1 LAST PART_NUMBER SHORT6
J 0
(500 5810);
DISPLAY 0.617021 (500 5810);
PAINT BLUE (500 5810);
DISPLAY INVISIBLE (500 5810);
FORCEPROP 2 LAST PACK_TYPE SM
J 0
(500 5900);
DISPLAY 0.617021 (500 5900);
PAINT SKYBLUE (500 5900);
FORCEPROP 1 LAST MATERIAL EMPTY
J 0
(500 5860);
DISPLAY 0.617021 (500 5860);
PAINT RED (500 5860);
FORCEPROP 1 LAST LOCATION PJ51
J 0
(375 5905);
DISPLAY 0.617021 (375 5905);
PAINT AQUA (375 5905);
FORCEPROP 0 LASTPIN (350 6050) $PN 1
J 2
(340 6060);
DISPLAY 0.617021 (340 6060);
PAINT MONO (340 6060);
FORCEPROP 0 LASTPIN (600 6050) $PN 2
J 0
(610 6060);
DISPLAY 0.617021 (610 6060);
PAINT MONO (610 6060);
FORCEPROP 1 LAST NEEDS_NO_SIZE TRUE
J 0
(475 6050);
DISPLAY 0.468085 (475 6050);
PAINT GREEN (475 6050);
DISPLAY INVISIBLE (475 6050);
FORCEPROP 2 LAST CDS_LIB pure_quanta
J 0
(475 6050);
DISPLAY INVISIBLE (475 6050);
FORCEPROP 1 LAST PATH I44
J 0
(400 6255);
DISPLAY 0.723404 (400 6255);
PAINT GREEN (400 6255);
DISPLAY INVISIBLE (400 6255);
FORCEPROP 1 LAST LOCATION PJ51
J 0
(400 6300);
DISPLAY 1.021277 (400 6300);
PAINT AQUA (400 6300);
DISPLAY INVISIBLE (400 6300);
FORCEPROP 0 LAST $SEC 1
J 0
(400 6300);
DISPLAY 0.680851 (400 6300);
PAINT MONO (400 6300);
DISPLAY INVISIBLE (400 6300);
FORCEPROP 0 LAST CDS_SEC 1
J 0
(400 6300);
DISPLAY 1.021277 (400 6300);
DISPLAY INVISIBLE (400 6300);
FORCEADD Q_RES..1
(550 6200);
FORCEPROP 1 LAST PART_NUMBER CS11002FB07
J 0
(675 6250);
DISPLAY 0.617021 (675 6250);
PAINT BLUE (675 6250);
DISPLAY INVISIBLE (675 6250);
FORCEPROP 1 LAST TOLERANCE 1%
J 0
(775 6200);
DISPLAY 0.617021 (775 6200);
PAINT SKYBLUE (775 6200);
FORCEPROP 1 LAST VALUE 100
J 2
(750 6200);
DISPLAY 0.617021 (750 6200);
PAINT SKYBLUE (750 6200);
FORCEPROP 1 LAST PACK_TYPE 0402LF
J 0
(850 6200);
DISPLAY 0.617021 (850 6200);
PAINT SKYBLUE (850 6200);
FORCEPROP 1 LAST WATTAGE 1/16W
J 2
(975 6300);
DISPLAY 0.617021 (975 6300);
PAINT SKYBLUE (975 6300);
FORCEPROP 1 LAST MATERIAL CHIP
J 0
(675 6300);
DISPLAY 0.617021 (675 6300);
PAINT SKYBLUE (675 6300);
FORCEPROP 1 LAST LOCATION PR569
J 0
(325 6200);
DISPLAY 0.617021 (325 6200);
PAINT AQUA (325 6200);
FORCEPROP 1 LASTPIN (450 6200) $PN 1
J 0
(462 6212);
DISPLAY 0.617021 (462 6212);
FORCEPROP 1 LASTPIN (650 6200) $PN 2
J 0
(612 6212);
DISPLAY 0.617021 (612 6212);
FORCEPROP 2 LAST CDS_LIB pure_quanta
J 0
(550 6200);
PAINT MONO (550 6200);
DISPLAY INVISIBLE (550 6200);
FORCEPROP 1 LAST PATH I45
J 0
(500 6350);
DISPLAY 0.978723 (500 6350);
PAINT WHITE (500 6350);
DISPLAY INVISIBLE (500 6350);
FORCEPROP 2 LAST $SEC 1
J 0
(500 6400);
DISPLAY 0.680851 (500 6400);
PAINT MONO (500 6400);
DISPLAY INVISIBLE (500 6400);
FORCEPROP 2 LAST CDS_SEC 1
J 0
(500 6400);
DISPLAY 1.021277 (500 6400);
DISPLAY INVISIBLE (500 6400);
FORCEADD Q_RES..1
(550 6625);
FORCEPROP 1 LAST PART_NUMBER CS11002FB07
J 0
(675 6675);
DISPLAY 0.617021 (675 6675);
PAINT BLUE (675 6675);
DISPLAY INVISIBLE (675 6675);
FORCEPROP 1 LAST VALUE 100
J 2
(750 6625);
DISPLAY 0.617021 (750 6625);
PAINT SKYBLUE (750 6625);
FORCEPROP 1 LAST MATERIAL CHIP
J 0
(675 6725);
DISPLAY 0.617021 (675 6725);
PAINT SKYBLUE (675 6725);
FORCEPROP 1 LAST PACK_TYPE 0402LF
J 0
(850 6625);
DISPLAY 0.617021 (850 6625);
PAINT SKYBLUE (850 6625);
FORCEPROP 1 LAST TOLERANCE 1%
J 0
(775 6625);
DISPLAY 0.617021 (775 6625);
PAINT SKYBLUE (775 6625);
FORCEPROP 1 LAST WATTAGE 1/16W
J 2
(975 6725);
DISPLAY 0.617021 (975 6725);
PAINT SKYBLUE (975 6725);
FORCEPROP 1 LAST LOCATION PR566
J 0
(325 6625);
DISPLAY 0.617021 (325 6625);
PAINT AQUA (325 6625);
FORCEPROP 1 LASTPIN (450 6625) $PN 1
J 0
(462 6637);
DISPLAY 0.617021 (462 6637);
FORCEPROP 1 LASTPIN (650 6625) $PN 2
J 0
(612 6637);
DISPLAY 0.617021 (612 6637);
FORCEPROP 2 LAST CDS_LIB pure_quanta
J 0
(550 6625);
PAINT MONO (550 6625);
DISPLAY INVISIBLE (550 6625);
FORCEPROP 1 LAST PATH I46
J 0
(500 6775);
DISPLAY 0.978723 (500 6775);
PAINT WHITE (500 6775);
DISPLAY INVISIBLE (500 6775);
FORCEPROP 2 LAST $SEC 1
J 0
(500 6825);
DISPLAY 0.680851 (500 6825);
PAINT MONO (500 6825);
DISPLAY INVISIBLE (500 6825);
FORCEPROP 2 LAST CDS_SEC 1
J 0
(500 6825);
DISPLAY 1.021277 (500 6825);
DISPLAY INVISIBLE (500 6825);
FORCEADD VCC15..1
(1050 6350);
FORCEPROP 3 LASTPIN (1050 6300) SIG_NAME PVCCFA_EHV_CPU1\g
J 0
(1060 6310);
DISPLAY 0.659574 (1060 6310);
PAINT MONO (1060 6310);
DISPLAY INVISIBLE (1060 6310);
FORCEPROP 1 LAST HDL_POWER PVCCFA_EHV_CPU1
J 1
(1050 6400);
DISPLAY 0.617021 (1050 6400);
PAINT GREEN (1050 6400);
FORCEPROP 2 LAST CDS_LIB logical_power
J 0
(1050 6350);
PAINT MONO (1050 6350);
DISPLAY INVISIBLE (1050 6350);
FORCEPROP 1 LAST PATH I47
J 0
(1100 6375);
DISPLAY 0.872340 (1100 6375);
PAINT AQUA (1100 6375);
DISPLAY INVISIBLE (1100 6375);
FORCEADD UNIVERSAL_GND..1
(1025 6525);
FORCEPROP 3 LASTPIN (1025 6575) SIG_NAME GND\g
J 0
(1035 6585);
DISPLAY 0.659574 (1035 6585);
PAINT MONO (1035 6585);
DISPLAY INVISIBLE (1035 6585);
FORCEPROP 1 LAST HDL_POWER GND
J 1
(1050 6450);
DISPLAY 0.872340 (1050 6450);
PAINT GREEN (1050 6450);
DISPLAY INVISIBLE (1050 6450);
FORCEPROP 2 LAST CDS_LIB logical_power
J 0
(1025 6525);
PAINT MONO (1025 6525);
DISPLAY INVISIBLE (1025 6525);
FORCEPROP 1 LAST PATH I48
J 0
(1100 6525);
DISPLAY 0.872340 (1100 6525);
PAINT AQUA (1100 6525);
DISPLAY INVISIBLE (1100 6525);
FORCEADD Q_RES..1
(1350 5050);
FORCEPROP 1 LAST PART_NUMBER CS21002FB06
J 0
(1475 5100);
DISPLAY 0.510638 (1475 5100);
PAINT BLUE (1475 5100);
DISPLAY INVISIBLE (1475 5100);
FORCEPROP 1 LAST VALUE 1K
J 2
(1525 5050);
DISPLAY 0.617021 (1525 5050);
PAINT SKYBLUE (1525 5050);
FORCEPROP 1 LAST PACK_TYPE 0402LF
J 0
(1625 5050);
DISPLAY 0.617021 (1625 5050);
PAINT SKYBLUE (1625 5050);
FORCEPROP 1 LAST TOLERANCE 1%
J 0
(1550 5050);
DISPLAY 0.617021 (1550 5050);
PAINT SKYBLUE (1550 5050);
FORCEPROP 1 LAST LOCATION R2569
J 0
(1125 5050);
DISPLAY 0.617021 (1125 5050);
PAINT AQUA (1125 5050);
FORCEPROP 1 LASTPIN (1250 5050) $PN 1
J 0
(1262 5062);
DISPLAY 0.617021 (1262 5062);
FORCEPROP 1 LASTPIN (1450 5050) $PN 2
J 0
(1412 5062);
DISPLAY 0.617021 (1412 5062);
FORCEPROP 2 LAST CDS_LIB pure_quanta
J 0
(1350 5050);
PAINT MONO (1350 5050);
DISPLAY INVISIBLE (1350 5050);
FORCEPROP 1 LAST WATTAGE 1/16W
J 2
(1725 5150);
DISPLAY 0.510638 (1725 5150);
PAINT SKYBLUE (1725 5150);
DISPLAY INVISIBLE (1725 5150);
FORCEPROP 1 LAST MATERIAL CHIP
J 0
(1475 5150);
DISPLAY 0.510638 (1475 5150);
PAINT SKYBLUE (1475 5150);
DISPLAY INVISIBLE (1475 5150);
FORCEPROP 1 LAST PATH I49
J 0
(1300 5200);
DISPLAY 0.978723 (1300 5200);
PAINT WHITE (1300 5200);
DISPLAY INVISIBLE (1300 5200);
FORCEPROP 2 LAST $SEC 1
J 0
(1300 5250);
DISPLAY 0.680851 (1300 5250);
PAINT MONO (1300 5250);
DISPLAY INVISIBLE (1300 5250);
FORCEPROP 2 LAST CDS_SEC 1
J 0
(1300 5250);
DISPLAY 1.021277 (1300 5250);
DISPLAY INVISIBLE (1300 5250);
FORCEADD OFFPAGE..1
(-725 6050);
FORCEPROP 2 LAST $XR0 47 
J 0
(-1006 6050);
DISPLAY 0.638298 (-1006 6050);
PAINT MONO (-1006 6050);
FORCEPROP 1 LAST COMMENT_BODY TRUE
J 0
(-600 5950);
DISPLAY 0.872340 (-600 5950);
PAINT GREEN (-600 5950);
DISPLAY INVISIBLE (-600 5950);
FORCEPROP 1 LAST OFFPAGE TRUE
J 0
(-400 5925);
DISPLAY 0.872340 (-400 5925);
PAINT GREEN (-400 5925);
DISPLAY INVISIBLE (-400 5925);
FORCEPROP 2 LAST CDS_LIB standard
J 0
(-725 6050);
DISPLAY INVISIBLE (-725 6050);
FORCEPROP 2 LAST PATH I5
J 0
(-1000 6100);
DISPLAY 1.021277 (-1000 6100);
DISPLAY INVISIBLE (-1000 6100);
FORCEADD Q_RES..1
(1350 5150);
FORCEPROP 1 LAST PART_NUMBER CS21002FB06
J 0
(1475 5200);
DISPLAY 0.617021 (1475 5200);
PAINT BLUE (1475 5200);
DISPLAY INVISIBLE (1475 5200);
FORCEPROP 1 LAST TOLERANCE 1%
J 0
(1550 5150);
DISPLAY 0.617021 (1550 5150);
PAINT SKYBLUE (1550 5150);
FORCEPROP 1 LAST MATERIAL CHIP
J 0
(1475 5250);
DISPLAY 0.617021 (1475 5250);
PAINT SKYBLUE (1475 5250);
FORCEPROP 1 LAST VALUE 1K
J 2
(1525 5150);
DISPLAY 0.617021 (1525 5150);
PAINT SKYBLUE (1525 5150);
FORCEPROP 1 LAST PACK_TYPE 0402LF
J 0
(1625 5150);
DISPLAY 0.617021 (1625 5150);
PAINT SKYBLUE (1625 5150);
FORCEPROP 1 LAST WATTAGE 1/16W
J 2
(1775 5250);
DISPLAY 0.617021 (1775 5250);
PAINT SKYBLUE (1775 5250);
FORCEPROP 1 LAST LOCATION R2568
J 0
(1125 5150);
DISPLAY 0.617021 (1125 5150);
PAINT AQUA (1125 5150);
FORCEPROP 1 LASTPIN (1250 5150) $PN 1
J 0
(1262 5162);
DISPLAY 0.617021 (1262 5162);
FORCEPROP 1 LASTPIN (1450 5150) $PN 2
J 0
(1412 5162);
DISPLAY 0.617021 (1412 5162);
FORCEPROP 2 LAST CDS_LIB pure_quanta
J 0
(1350 5150);
PAINT MONO (1350 5150);
DISPLAY INVISIBLE (1350 5150);
FORCEPROP 1 LAST PATH I50
J 0
(1300 5300);
DISPLAY 0.978723 (1300 5300);
PAINT WHITE (1300 5300);
DISPLAY INVISIBLE (1300 5300);
FORCEPROP 2 LAST $SEC 1
J 0
(1300 5350);
DISPLAY 0.680851 (1300 5350);
PAINT MONO (1300 5350);
DISPLAY INVISIBLE (1300 5350);
FORCEPROP 2 LAST CDS_SEC 1
J 0
(1300 5350);
DISPLAY 1.021277 (1300 5350);
DISPLAY INVISIBLE (1300 5350);
FORCEADD Q_CAP..1
(1975 5875);
FORCEPROP 1 LAST PART_NUMBER TMP_QCH2336K1B12
J 0
(2025 5700);
DISPLAY 0.617021 (2025 5700);
PAINT BLUE (2025 5700);
DISPLAY INVISIBLE (2025 5700);
FORCEPROP 1 LAST MATERIAL X7R
J 0
(2025 5800);
DISPLAY 0.617021 (2025 5800);
PAINT SKYBLUE (2025 5800);
FORCEPROP 1 LAST TOLERANCE 10%
J 0
(2025 5850);
DISPLAY 0.617021 (2025 5850);
PAINT SKYBLUE (2025 5850);
FORCEPROP 1 LAST VALUE 3300PF
J 0
(2025 5950);
DISPLAY 0.617021 (2025 5950);
PAINT SKYBLUE (2025 5950);
FORCEPROP 1 LAST VOLTAGE 50V
J 0
(2025 5900);
DISPLAY 0.617021 (2025 5900);
PAINT SKYBLUE (2025 5900);
FORCEPROP 1 LAST PACK_TYPE 0402
J 0
(2025 5750);
DISPLAY 0.617021 (2025 5750);
PAINT SKYBLUE (2025 5750);
FORCEPROP 1 LAST LOCATION PC469
J 0
(2025 6000);
DISPLAY 0.617021 (2025 6000);
PAINT AQUA (2025 6000);
FORCEPROP 1 LASTPIN (1975 5975) $PN 1
J 0
(1985 5955);
DISPLAY 0.617021 (1985 5955);
PAINT MONO (1985 5955);
FORCEPROP 1 LASTPIN (1975 5775) $PN 2
J 0
(1985 5755);
DISPLAY 0.617021 (1985 5755);
PAINT MONO (1985 5755);
FORCEPROP 2 LAST CDS_LIB pure_quanta
J 0
(1975 5875);
DISPLAY INVISIBLE (1975 5875);
FORCEPROP 1 LAST PATH I51
J 0
(2025 6025);
DISPLAY 0.978723 (2025 6025);
PAINT WHITE (2025 6025);
DISPLAY INVISIBLE (2025 6025);
FORCEPROP 1 LAST LOCATION PC469
J 0
(2025 6000);
DISPLAY 1.021277 (2025 6000);
PAINT AQUA (2025 6000);
DISPLAY INVISIBLE (2025 6000);
FORCEPROP 0 LAST $SEC 1
J 0
(2025 6000);
DISPLAY 0.680851 (2025 6000);
PAINT MONO (2025 6000);
DISPLAY INVISIBLE (2025 6000);
FORCEPROP 0 LAST CDS_SEC 1
J 0
(2025 6000);
DISPLAY 1.021277 (2025 6000);
DISPLAY INVISIBLE (2025 6000);
FORCEADD Q_RES..1
(1525 6050);
FORCEPROP 1 LAST PART_NUMBER CS00002JB13
J 0
(1650 6100);
DISPLAY 0.617021 (1650 6100);
PAINT BLUE (1650 6100);
DISPLAY INVISIBLE (1650 6100);
FORCEPROP 1 LAST WATTAGE 1/16W
J 2
(1950 6150);
DISPLAY 0.617021 (1950 6150);
PAINT SKYBLUE (1950 6150);
FORCEPROP 1 LAST MATERIAL CHIP
J 0
(1650 6150);
DISPLAY 0.617021 (1650 6150);
PAINT SKYBLUE (1650 6150);
FORCEPROP 1 LAST TOLERANCE 5%
J 0
(1700 6050);
DISPLAY 0.617021 (1700 6050);
PAINT SKYBLUE (1700 6050);
FORCEPROP 1 LAST VALUE 0
J 2
(1675 6050);
DISPLAY 0.617021 (1675 6050);
PAINT SKYBLUE (1675 6050);
FORCEPROP 1 LAST PACK_TYPE 0402LF
J 0
(1775 6050);
DISPLAY 0.617021 (1775 6050);
PAINT SKYBLUE (1775 6050);
FORCEPROP 1 LAST LOCATION PR274
J 0
(1325 6050);
DISPLAY 0.617021 (1325 6050);
PAINT AQUA (1325 6050);
FORCEPROP 1 LASTPIN (1425 6050) $PN 1
J 0
(1437 6062);
DISPLAY 0.617021 (1437 6062);
PAINT MONO (1437 6062);
FORCEPROP 1 LASTPIN (1625 6050) $PN 2
J 0
(1587 6062);
DISPLAY 0.617021 (1587 6062);
PAINT MONO (1587 6062);
FORCEPROP 2 LAST CDS_LIB pure_quanta
J 0
(1525 6050);
DISPLAY INVISIBLE (1525 6050);
FORCEPROP 1 LAST PATH I52
J 0
(1475 6200);
DISPLAY 0.978723 (1475 6200);
PAINT WHITE (1475 6200);
DISPLAY INVISIBLE (1475 6200);
FORCEPROP 1 LAST LOCATION PR274
J 0
(1475 6150);
DISPLAY 1.021277 (1475 6150);
PAINT AQUA (1475 6150);
DISPLAY INVISIBLE (1475 6150);
FORCEPROP 0 LAST $SEC 1
J 0
(1475 6150);
DISPLAY 0.680851 (1475 6150);
PAINT MONO (1475 6150);
DISPLAY INVISIBLE (1475 6150);
FORCEPROP 0 LAST CDS_SEC 1
J 0
(1475 6150);
DISPLAY 1.021277 (1475 6150);
DISPLAY INVISIBLE (1475 6150);
FORCEADD Q_CAP..1
(1975 6975);
FORCEPROP 1 LAST PART_NUMBER TMP_QCH2336K1B12
J 0
(2025 6800);
DISPLAY 0.617021 (2025 6800);
PAINT BLUE (2025 6800);
DISPLAY INVISIBLE (2025 6800);
FORCEPROP 1 LAST VALUE 3300PF
J 0
(2025 7050);
DISPLAY 0.617021 (2025 7050);
PAINT SKYBLUE (2025 7050);
FORCEPROP 1 LAST MATERIAL X7R
J 0
(2025 6900);
DISPLAY 0.617021 (2025 6900);
PAINT SKYBLUE (2025 6900);
FORCEPROP 1 LAST TOLERANCE 10%
J 0
(2025 6950);
DISPLAY 0.617021 (2025 6950);
PAINT SKYBLUE (2025 6950);
FORCEPROP 1 LAST VOLTAGE 50V
J 0
(2025 7000);
DISPLAY 0.617021 (2025 7000);
PAINT SKYBLUE (2025 7000);
FORCEPROP 1 LAST PACK_TYPE 0402
J 0
(2025 6850);
DISPLAY 0.617021 (2025 6850);
PAINT SKYBLUE (2025 6850);
FORCEPROP 1 LAST LOCATION PC468
J 0
(2025 7100);
DISPLAY 0.617021 (2025 7100);
PAINT AQUA (2025 7100);
FORCEPROP 1 LASTPIN (1975 7075) $PN 1
J 0
(1985 7055);
DISPLAY 0.617021 (1985 7055);
PAINT MONO (1985 7055);
FORCEPROP 1 LASTPIN (1975 6875) $PN 2
J 0
(1985 6855);
DISPLAY 0.617021 (1985 6855);
PAINT MONO (1985 6855);
FORCEPROP 2 LAST CDS_LIB pure_quanta
J 0
(1975 6975);
DISPLAY INVISIBLE (1975 6975);
FORCEPROP 1 LAST PATH I53
J 0
(2025 7125);
DISPLAY 0.978723 (2025 7125);
PAINT WHITE (2025 7125);
DISPLAY INVISIBLE (2025 7125);
FORCEPROP 1 LAST LOCATION PC468
J 0
(2025 7100);
DISPLAY 1.021277 (2025 7100);
PAINT AQUA (2025 7100);
DISPLAY INVISIBLE (2025 7100);
FORCEPROP 0 LAST $SEC 1
J 0
(2025 7100);
DISPLAY 0.680851 (2025 7100);
PAINT MONO (2025 7100);
DISPLAY INVISIBLE (2025 7100);
FORCEPROP 0 LAST CDS_SEC 1
J 0
(2025 7100);
DISPLAY 1.021277 (2025 7100);
DISPLAY INVISIBLE (2025 7100);
FORCEADD Q_SHORT..1
(475 7150);
FORCEPROP 1 LAST PART_NUMBER SHORT6
J 0
(500 6910);
DISPLAY 0.617021 (500 6910);
PAINT BLUE (500 6910);
DISPLAY INVISIBLE (500 6910);
FORCEPROP 1 LAST MATERIAL EMPTY
J 0
(500 6960);
DISPLAY 0.617021 (500 6960);
PAINT RED (500 6960);
FORCEPROP 2 LAST PACK_TYPE SM
J 0
(500 7000);
DISPLAY 0.617021 (500 7000);
PAINT SKYBLUE (500 7000);
FORCEPROP 1 LAST LOCATION PJ50
J 0
(375 7005);
DISPLAY 0.617021 (375 7005);
PAINT AQUA (375 7005);
FORCEPROP 0 LASTPIN (350 7150) $PN 1
J 2
(340 7160);
DISPLAY 0.617021 (340 7160);
PAINT MONO (340 7160);
FORCEPROP 0 LASTPIN (600 7150) $PN 2
J 0
(610 7160);
DISPLAY 0.617021 (610 7160);
PAINT MONO (610 7160);
FORCEPROP 1 LAST NEEDS_NO_SIZE TRUE
J 0
(475 7150);
DISPLAY 0.468085 (475 7150);
PAINT GREEN (475 7150);
DISPLAY INVISIBLE (475 7150);
FORCEPROP 2 LAST CDS_LIB pure_quanta
J 0
(475 7150);
DISPLAY INVISIBLE (475 7150);
FORCEPROP 1 LAST PATH I54
J 0
(400 7355);
DISPLAY 0.723404 (400 7355);
PAINT GREEN (400 7355);
DISPLAY INVISIBLE (400 7355);
FORCEPROP 1 LAST LOCATION PJ50
J 0
(400 7400);
DISPLAY 1.021277 (400 7400);
PAINT AQUA (400 7400);
DISPLAY INVISIBLE (400 7400);
FORCEPROP 0 LAST $SEC 1
J 0
(400 7400);
DISPLAY 0.680851 (400 7400);
PAINT MONO (400 7400);
DISPLAY INVISIBLE (400 7400);
FORCEPROP 0 LAST CDS_SEC 1
J 0
(400 7400);
DISPLAY 1.021277 (400 7400);
DISPLAY INVISIBLE (400 7400);
FORCEADD Q_RES..1
(550 7300);
FORCEPROP 1 LAST PART_NUMBER CS11002FB07
J 0
(675 7350);
DISPLAY 0.617021 (675 7350);
PAINT BLUE (675 7350);
DISPLAY INVISIBLE (675 7350);
FORCEPROP 1 LAST WATTAGE 1/16W
J 2
(975 7400);
DISPLAY 0.617021 (975 7400);
PAINT SKYBLUE (975 7400);
FORCEPROP 1 LAST MATERIAL CHIP
J 0
(675 7400);
DISPLAY 0.617021 (675 7400);
PAINT SKYBLUE (675 7400);
FORCEPROP 1 LAST VALUE 100
J 2
(750 7300);
DISPLAY 0.617021 (750 7300);
PAINT SKYBLUE (750 7300);
FORCEPROP 1 LAST PACK_TYPE 0402LF
J 0
(850 7300);
DISPLAY 0.617021 (850 7300);
PAINT SKYBLUE (850 7300);
FORCEPROP 1 LAST TOLERANCE 1%
J 0
(775 7300);
DISPLAY 0.617021 (775 7300);
PAINT SKYBLUE (775 7300);
FORCEPROP 1 LAST LOCATION PR568
J 0
(325 7300);
DISPLAY 0.617021 (325 7300);
PAINT AQUA (325 7300);
FORCEPROP 1 LASTPIN (450 7300) $PN 1
J 0
(462 7312);
DISPLAY 0.617021 (462 7312);
FORCEPROP 1 LASTPIN (650 7300) $PN 2
J 0
(612 7312);
DISPLAY 0.617021 (612 7312);
FORCEPROP 2 LAST CDS_LIB pure_quanta
J 0
(550 7300);
PAINT MONO (550 7300);
DISPLAY INVISIBLE (550 7300);
FORCEPROP 1 LAST PATH I55
J 0
(500 7450);
DISPLAY 0.978723 (500 7450);
PAINT WHITE (500 7450);
DISPLAY INVISIBLE (500 7450);
FORCEPROP 2 LAST $SEC 1
J 0
(500 7500);
DISPLAY 0.680851 (500 7500);
PAINT MONO (500 7500);
DISPLAY INVISIBLE (500 7500);
FORCEPROP 2 LAST CDS_SEC 1
J 0
(500 7500);
DISPLAY 1.021277 (500 7500);
DISPLAY INVISIBLE (500 7500);
FORCEADD VCC15..1
(1050 7450);
FORCEPROP 3 LASTPIN (1050 7400) SIG_NAME PVCCINFAON_CPU1\g
J 0
(1060 7410);
DISPLAY 0.659574 (1060 7410);
PAINT MONO (1060 7410);
DISPLAY INVISIBLE (1060 7410);
FORCEPROP 1 LAST HDL_POWER PVCCINFAON_CPU1
J 1
(1050 7500);
DISPLAY 0.617021 (1050 7500);
PAINT GREEN (1050 7500);
FORCEPROP 2 LAST CDS_LIB logical_power
J 0
(1050 7450);
DISPLAY INVISIBLE (1050 7450);
FORCEPROP 1 LAST PATH I56
J 0
(1100 7475);
DISPLAY 0.872340 (1100 7475);
PAINT AQUA (1100 7475);
DISPLAY INVISIBLE (1100 7475);
FORCEADD Q_RES..1
(1175 7850);
FORCEPROP 1 LAST PART_NUMBER CS00002JB13
J 0
(1300 7900);
DISPLAY 0.617021 (1300 7900);
PAINT BLUE (1300 7900);
DISPLAY INVISIBLE (1300 7900);
FORCEPROP 1 LAST PACK_TYPE 0402LF
J 0
(1425 7850);
DISPLAY 0.617021 (1425 7850);
PAINT SKYBLUE (1425 7850);
FORCEPROP 1 LAST TOLERANCE 5%
J 0
(1350 7850);
DISPLAY 0.617021 (1350 7850);
PAINT SKYBLUE (1350 7850);
FORCEPROP 1 LAST VALUE 0
J 2
(1325 7850);
DISPLAY 0.617021 (1325 7850);
PAINT SKYBLUE (1325 7850);
FORCEPROP 1 LAST MATERIAL CHIP
J 0
(1300 7950);
DISPLAY 0.617021 (1300 7950);
PAINT SKYBLUE (1300 7950);
FORCEPROP 1 LAST WATTAGE 1/16W
J 2
(1600 7950);
DISPLAY 0.617021 (1600 7950);
PAINT SKYBLUE (1600 7950);
FORCEPROP 1 LAST LOCATION R2563
J 0
(925 7850);
DISPLAY 0.617021 (925 7850);
PAINT AQUA (925 7850);
FORCEPROP 1 LASTPIN (1075 7850) $PN 1
J 0
(1087 7862);
DISPLAY 0.617021 (1087 7862);
PAINT MONO (1087 7862);
FORCEPROP 1 LASTPIN (1275 7850) $PN 2
J 0
(1237 7862);
DISPLAY 0.617021 (1237 7862);
PAINT MONO (1237 7862);
FORCEPROP 2 LAST CDS_LIB pure_quanta
J 0
(1175 7850);
DISPLAY INVISIBLE (1175 7850);
FORCEPROP 1 LAST PATH I57
J 0
(1125 8000);
DISPLAY 0.978723 (1125 8000);
PAINT WHITE (1125 8000);
DISPLAY INVISIBLE (1125 8000);
FORCEPROP 1 LAST LOCATION R2563
J 0
(1125 7950);
DISPLAY 1.021277 (1125 7950);
PAINT AQUA (1125 7950);
DISPLAY INVISIBLE (1125 7950);
FORCEPROP 0 LAST $SEC 1
J 0
(1125 7950);
DISPLAY 0.680851 (1125 7950);
PAINT MONO (1125 7950);
DISPLAY INVISIBLE (1125 7950);
FORCEPROP 0 LAST CDS_SEC 1
J 0
(1125 7950);
DISPLAY 1.021277 (1125 7950);
DISPLAY INVISIBLE (1125 7950);
FORCEADD Q_RES..1
(1175 8000);
FORCEPROP 1 LAST PART_NUMBER CS00002JB13
J 0
(1075 8050);
DISPLAY 0.319149 (1075 8050);
DISPLAY INVISIBLE (1075 8050);
FORCEPROP 1 LAST MATERIAL CHIP
J 0
(1450 8000);
DISPLAY 0.638298 (1450 8000);
FORCEPROP 1 LAST TOLERANCE 5%
J 0
(1375 8000);
DISPLAY 0.638298 (1375 8000);
FORCEPROP 1 LAST VALUE 0
J 2
(1350 8000);
DISPLAY 0.638298 (1350 8000);
FORCEPROP 1 LAST PACK_TYPE 0402LF
J 0
(1075 8075);
DISPLAY 0.319149 (1075 8075);
FORCEPROP 1 LAST WATTAGE 1/16W
J 2
(1250 8075);
DISPLAY 0.319149 (1250 8075);
FORCEPROP 1 LAST LOCATION R4594
J 0
(825 8000);
DISPLAY 0.638298 (825 8000);
FORCEPROP 1 LASTPIN (1075 8000) $PN 1
J 0
(1087 8012);
DISPLAY 0.787234 (1087 8012);
PAINT MONO (1087 8012);
FORCEPROP 1 LASTPIN (1275 8000) $PN 2
J 0
(1237 8012);
DISPLAY 0.787234 (1237 8012);
PAINT MONO (1237 8012);
FORCEPROP 2 LAST SEC_TYPE 0402LF
J 0
(1125 8200);
DISPLAY 1.021277 (1125 8200);
DISPLAY INVISIBLE (1125 8200);
FORCEPROP 2 LAST CDS_LIB pure_quanta
J 0
(1175 8000);
DISPLAY INVISIBLE (1175 8000);
FORCEPROP 1 LAST PATH I58
J 0
(1125 8150);
DISPLAY 0.978723 (1125 8150);
PAINT WHITE (1125 8150);
DISPLAY INVISIBLE (1125 8150);
FORCEPROP 2 LAST SEC 1
J 0
(1125 8200);
DISPLAY 0.680851 (1125 8200);
PAINT MONO (1125 8200);
DISPLAY INVISIBLE (1125 8200);
FORCEADD Q_RES..1
(1175 8400);
FORCEPROP 1 LAST PART_NUMBER CS00002JB13
J 0
(1300 8450);
DISPLAY 0.617021 (1300 8450);
PAINT BLUE (1300 8450);
DISPLAY INVISIBLE (1300 8450);
FORCEPROP 1 LAST WATTAGE 1/16W
J 2
(1600 8500);
DISPLAY 0.617021 (1600 8500);
PAINT SKYBLUE (1600 8500);
FORCEPROP 1 LAST PACK_TYPE 0402LF
J 0
(1425 8400);
DISPLAY 0.617021 (1425 8400);
PAINT SKYBLUE (1425 8400);
FORCEPROP 1 LAST TOLERANCE 5%
J 0
(1350 8400);
DISPLAY 0.617021 (1350 8400);
PAINT SKYBLUE (1350 8400);
FORCEPROP 1 LAST MATERIAL CHIP
J 0
(1300 8500);
DISPLAY 0.617021 (1300 8500);
PAINT SKYBLUE (1300 8500);
FORCEPROP 1 LAST VALUE 0
J 2
(1325 8400);
DISPLAY 0.617021 (1325 8400);
PAINT SKYBLUE (1325 8400);
FORCEPROP 1 LAST LOCATION R2561
J 0
(925 8400);
DISPLAY 0.617021 (925 8400);
PAINT AQUA (925 8400);
FORCEPROP 1 LASTPIN (1075 8400) $PN 1
J 0
(1087 8412);
DISPLAY 0.617021 (1087 8412);
PAINT MONO (1087 8412);
FORCEPROP 1 LASTPIN (1275 8400) $PN 2
J 0
(1237 8412);
DISPLAY 0.617021 (1237 8412);
PAINT MONO (1237 8412);
FORCEPROP 2 LAST CDS_LIB pure_quanta
J 0
(1175 8400);
DISPLAY INVISIBLE (1175 8400);
FORCEPROP 1 LAST PATH I59
J 0
(1125 8550);
DISPLAY 0.978723 (1125 8550);
PAINT WHITE (1125 8550);
DISPLAY INVISIBLE (1125 8550);
FORCEPROP 1 LAST LOCATION R2561
J 0
(1125 8500);
DISPLAY 1.021277 (1125 8500);
PAINT AQUA (1125 8500);
DISPLAY INVISIBLE (1125 8500);
FORCEPROP 0 LAST $SEC 1
J 0
(1125 8500);
DISPLAY 0.680851 (1125 8500);
PAINT MONO (1125 8500);
DISPLAY INVISIBLE (1125 8500);
FORCEPROP 0 LAST CDS_SEC 1
J 0
(1125 8500);
DISPLAY 1.021277 (1125 8500);
DISPLAY INVISIBLE (1125 8500);
FORCEADD OFFPAGE..1
(-725 6775);
FORCEPROP 2 LAST $XR0 47 
J 0
(-1006 6775);
DISPLAY 0.638298 (-1006 6775);
PAINT MONO (-1006 6775);
FORCEPROP 1 LAST COMMENT_BODY TRUE
J 0
(-600 6675);
DISPLAY 0.872340 (-600 6675);
PAINT GREEN (-600 6675);
DISPLAY INVISIBLE (-600 6675);
FORCEPROP 1 LAST OFFPAGE TRUE
J 0
(-400 6650);
DISPLAY 0.872340 (-400 6650);
PAINT GREEN (-400 6650);
DISPLAY INVISIBLE (-400 6650);
FORCEPROP 2 LAST CDS_LIB standard
J 0
(-725 6775);
DISPLAY INVISIBLE (-725 6775);
FORCEPROP 2 LAST PATH I6
J 0
(-1000 6825);
DISPLAY 1.021277 (-1000 6825);
DISPLAY INVISIBLE (-1000 6825);
FORCEADD Q_RES..1
(1175 8550);
FORCEPROP 1 LAST PART_NUMBER CS00002JB13
J 0
(1300 8600);
DISPLAY 0.617021 (1300 8600);
PAINT BLUE (1300 8600);
DISPLAY INVISIBLE (1300 8600);
FORCEPROP 1 LAST MATERIAL CHIP
J 0
(1300 8650);
DISPLAY 0.617021 (1300 8650);
PAINT SKYBLUE (1300 8650);
FORCEPROP 1 LAST PACK_TYPE 0402LF
J 0
(1425 8550);
DISPLAY 0.617021 (1425 8550);
PAINT SKYBLUE (1425 8550);
FORCEPROP 1 LAST WATTAGE 1/16W
J 2
(1600 8650);
DISPLAY 0.617021 (1600 8650);
PAINT SKYBLUE (1600 8650);
FORCEPROP 1 LAST TOLERANCE 5%
J 0
(1350 8550);
DISPLAY 0.617021 (1350 8550);
PAINT SKYBLUE (1350 8550);
FORCEPROP 1 LAST VALUE 0
J 2
(1325 8550);
DISPLAY 0.617021 (1325 8550);
PAINT SKYBLUE (1325 8550);
FORCEPROP 1 LAST LOCATION R2560
J 0
(925 8550);
DISPLAY 0.617021 (925 8550);
PAINT AQUA (925 8550);
FORCEPROP 1 LASTPIN (1075 8550) $PN 1
J 0
(1087 8562);
DISPLAY 0.617021 (1087 8562);
PAINT MONO (1087 8562);
FORCEPROP 1 LASTPIN (1275 8550) $PN 2
J 0
(1237 8562);
DISPLAY 0.617021 (1237 8562);
PAINT MONO (1237 8562);
FORCEPROP 2 LAST CDS_LIB pure_quanta
J 0
(1175 8550);
DISPLAY INVISIBLE (1175 8550);
FORCEPROP 1 LAST PATH I60
J 0
(1125 8700);
DISPLAY 0.978723 (1125 8700);
PAINT WHITE (1125 8700);
DISPLAY INVISIBLE (1125 8700);
FORCEPROP 1 LAST LOCATION R2560
J 0
(1125 8650);
DISPLAY 1.021277 (1125 8650);
PAINT AQUA (1125 8650);
DISPLAY INVISIBLE (1125 8650);
FORCEPROP 0 LAST $SEC 1
J 0
(1125 8650);
DISPLAY 0.680851 (1125 8650);
PAINT MONO (1125 8650);
DISPLAY INVISIBLE (1125 8650);
FORCEPROP 0 LAST CDS_SEC 1
J 0
(1125 8650);
DISPLAY 1.021277 (1125 8650);
DISPLAY INVISIBLE (1125 8650);
FORCEADD Q_RES..1
(1175 8700);
FORCEPROP 1 LAST PART_NUMBER CS11502FB07
J 0
(1300 8750);
DISPLAY 0.617021 (1300 8750);
PAINT BLUE (1300 8750);
DISPLAY INVISIBLE (1300 8750);
FORCEPROP 1 LAST MATERIAL CHIP
J 0
(1300 8800);
DISPLAY 0.617021 (1300 8800);
PAINT SKYBLUE (1300 8800);
FORCEPROP 1 LAST VALUE 150
J 2
(1400 8700);
DISPLAY 0.617021 (1400 8700);
PAINT SKYBLUE (1400 8700);
FORCEPROP 1 LAST TOLERANCE 1%
J 0
(1425 8700);
DISPLAY 0.617021 (1425 8700);
PAINT SKYBLUE (1425 8700);
FORCEPROP 1 LAST WATTAGE 1/16W
J 2
(1600 8800);
DISPLAY 0.617021 (1600 8800);
PAINT SKYBLUE (1600 8800);
FORCEPROP 1 LAST PACK_TYPE 0402LF
J 0
(1525 8700);
DISPLAY 0.617021 (1525 8700);
PAINT SKYBLUE (1525 8700);
FORCEPROP 1 LAST LOCATION R2559
J 0
(925 8700);
DISPLAY 0.617021 (925 8700);
PAINT AQUA (925 8700);
FORCEPROP 1 LASTPIN (1075 8700) $PN 1
J 0
(1087 8712);
DISPLAY 0.617021 (1087 8712);
PAINT MONO (1087 8712);
FORCEPROP 1 LASTPIN (1275 8700) $PN 2
J 0
(1237 8712);
DISPLAY 0.617021 (1237 8712);
PAINT MONO (1237 8712);
FORCEPROP 2 LAST CDS_LIB pure_quanta
J 0
(1175 8700);
DISPLAY INVISIBLE (1175 8700);
FORCEPROP 1 LAST PATH I61
J 0
(1125 8850);
DISPLAY 0.978723 (1125 8850);
PAINT WHITE (1125 8850);
DISPLAY INVISIBLE (1125 8850);
FORCEPROP 1 LAST LOCATION R2559
J 0
(1325 8775);
DISPLAY 1.021277 (1325 8775);
PAINT AQUA (1325 8775);
DISPLAY INVISIBLE (1325 8775);
FORCEPROP 0 LAST $SEC 1
J 0
(1325 8775);
DISPLAY 0.680851 (1325 8775);
PAINT MONO (1325 8775);
DISPLAY INVISIBLE (1325 8775);
FORCEPROP 0 LAST CDS_SEC 1
J 0
(1325 8775);
DISPLAY 1.021277 (1325 8775);
DISPLAY INVISIBLE (1325 8775);
FORCEADD Q_RES..1
(1525 7150);
FORCEPROP 1 LAST PART_NUMBER CS00002JB13
J 0
(1650 7200);
DISPLAY 0.617021 (1650 7200);
PAINT BLUE (1650 7200);
DISPLAY INVISIBLE (1650 7200);
FORCEPROP 1 LAST TOLERANCE 5%
J 0
(1700 7150);
DISPLAY 0.617021 (1700 7150);
PAINT SKYBLUE (1700 7150);
FORCEPROP 1 LAST VALUE 0
J 2
(1675 7150);
DISPLAY 0.617021 (1675 7150);
PAINT SKYBLUE (1675 7150);
FORCEPROP 1 LAST PACK_TYPE 0402LF
J 0
(1775 7150);
DISPLAY 0.617021 (1775 7150);
PAINT SKYBLUE (1775 7150);
FORCEPROP 1 LAST WATTAGE 1/16W
J 2
(1950 7250);
DISPLAY 0.617021 (1950 7250);
PAINT SKYBLUE (1950 7250);
FORCEPROP 1 LAST MATERIAL CHIP
J 0
(1650 7250);
DISPLAY 0.617021 (1650 7250);
PAINT SKYBLUE (1650 7250);
FORCEPROP 1 LAST LOCATION PR273
J 0
(1325 7150);
DISPLAY 0.617021 (1325 7150);
PAINT AQUA (1325 7150);
FORCEPROP 1 LASTPIN (1425 7150) $PN 1
J 0
(1437 7162);
DISPLAY 0.617021 (1437 7162);
PAINT MONO (1437 7162);
FORCEPROP 1 LASTPIN (1625 7150) $PN 2
J 0
(1587 7162);
DISPLAY 0.617021 (1587 7162);
PAINT MONO (1587 7162);
FORCEPROP 2 LAST CDS_LIB pure_quanta
J 0
(1525 7150);
DISPLAY INVISIBLE (1525 7150);
FORCEPROP 1 LAST PATH I62
J 0
(1475 7300);
DISPLAY 0.978723 (1475 7300);
PAINT WHITE (1475 7300);
DISPLAY INVISIBLE (1475 7300);
FORCEPROP 1 LAST LOCATION PR273
J 0
(1475 7250);
DISPLAY 1.021277 (1475 7250);
PAINT AQUA (1475 7250);
DISPLAY INVISIBLE (1475 7250);
FORCEPROP 0 LAST $SEC 1
J 0
(1475 7250);
DISPLAY 0.680851 (1475 7250);
PAINT MONO (1475 7250);
DISPLAY INVISIBLE (1475 7250);
FORCEPROP 0 LAST CDS_SEC 1
J 0
(1475 7250);
DISPLAY 1.021277 (1475 7250);
DISPLAY INVISIBLE (1475 7250);
FORCEADD Q_CAP..2
(2000 8875);
FORCEPROP 1 LAST PART_NUMBER TMP_QCH21006JB10
J 1
(2275 8825);
DISPLAY 0.617021 (2275 8825);
PAINT BLUE (2275 8825);
DISPLAY INVISIBLE (2275 8825);
FORCEPROP 1 LAST TOLERANCE 5%
J 2
(2650 8825);
DISPLAY 0.617021 (2650 8825);
PAINT SKYBLUE (2650 8825);
FORCEPROP 1 LAST PACK_TYPE 0402
J 1
(2550 8775);
DISPLAY 0.617021 (2550 8775);
PAINT SKYBLUE (2550 8775);
FORCEPROP 1 LAST MATERIAL X7R
J 0
(2475 8875);
DISPLAY 0.617021 (2475 8875);
PAINT SKYBLUE (2475 8875);
FORCEPROP 1 LAST VOLTAGE 50V
J 0
(2350 8875);
DISPLAY 0.617021 (2350 8875);
PAINT SKYBLUE (2350 8875);
FORCEPROP 1 LAST VALUE 1000PF
J 2
(2325 8875);
DISPLAY 0.617021 (2325 8875);
PAINT SKYBLUE (2325 8875);
FORCEPROP 1 LAST LOCATION C2451
J 1
(1800 8875);
DISPLAY 0.617021 (1800 8875);
PAINT AQUA (1800 8875);
FORCEPROP 1 LASTPIN (1900 8875) $PN 1
J 0
(1890 8890);
DISPLAY 0.617021 (1890 8890);
PAINT MONO (1890 8890);
FORCEPROP 1 LASTPIN (2100 8875) $PN 2
J 0
(2085 8890);
DISPLAY 0.617021 (2085 8890);
PAINT MONO (2085 8890);
FORCEPROP 2 LAST CDS_LIB pure_quanta
J 0
(2000 8875);
DISPLAY INVISIBLE (2000 8875);
FORCEPROP 1 LAST PATH I63
J 0
(2000 9075);
DISPLAY 0.978723 (2000 9075);
PAINT WHITE (2000 9075);
DISPLAY INVISIBLE (2000 9075);
FORCEPROP 1 LAST LOCATION C2451
J 0
(1950 8975);
DISPLAY 1.021277 (1950 8975);
PAINT AQUA (1950 8975);
DISPLAY INVISIBLE (1950 8975);
FORCEPROP 0 LAST $SEC 1
J 0
(1950 8975);
DISPLAY 0.680851 (1950 8975);
PAINT MONO (1950 8975);
DISPLAY INVISIBLE (1950 8975);
FORCEPROP 0 LAST CDS_SEC 1
J 0
(1950 8975);
DISPLAY 1.021277 (1950 8975);
DISPLAY INVISIBLE (1950 8975);
FORCEADD UNIVERSAL_GND..1
R 1
(2725 8875);
FORCEPROP 3 LASTPIN (2675 8875) SIG_NAME GND\g
J 0
(2685 8885);
DISPLAY 0.659574 (2685 8885);
PAINT MONO (2685 8885);
DISPLAY INVISIBLE (2685 8885);
FORCEPROP 1 LAST HDL_POWER GND
R 1
J 1
(2800 8900);
DISPLAY 0.872340 (2800 8900);
PAINT GREEN (2800 8900);
DISPLAY INVISIBLE (2800 8900);
FORCEPROP 2 LAST CDS_LIB logical_power
J 0
(2725 8875);
PAINT MONO (2725 8875);
DISPLAY INVISIBLE (2725 8875);
FORCEPROP 1 LAST PATH I64
R 1
J 0
(2725 8950);
DISPLAY 0.872340 (2725 8950);
PAINT AQUA (2725 8950);
DISPLAY INVISIBLE (2725 8950);
FORCEADD UNIVERSAL_GND..1
(4375 3550);
FORCEPROP 3 LASTPIN (4375 3600) SIG_NAME GND\g
J 0
(4385 3610);
DISPLAY 0.659574 (4385 3610);
PAINT MONO (4385 3610);
DISPLAY INVISIBLE (4385 3610);
FORCEPROP 1 LAST HDL_POWER GND
J 1
(4400 3475);
DISPLAY 0.872340 (4400 3475);
PAINT GREEN (4400 3475);
DISPLAY INVISIBLE (4400 3475);
FORCEPROP 2 LAST CDS_LIB logical_power
J 0
(4375 3550);
PAINT MONO (4375 3550);
DISPLAY INVISIBLE (4375 3550);
FORCEPROP 1 LAST PATH I65
J 0
(4450 3550);
DISPLAY 0.872340 (4450 3550);
PAINT AQUA (4450 3550);
DISPLAY INVISIBLE (4450 3550);
FORCEADD Q_CAP..1
(4375 3775);
FORCEPROP 1 LAST PART_NUMBER TMP_QCH14706KB18
J 0
(4425 3575);
DISPLAY 0.617021 (4425 3575);
PAINT BLUE (4425 3575);
DISPLAY INVISIBLE (4425 3575);
FORCEPROP 1 LAST VALUE 470PF
J 0
(4425 3825);
DISPLAY 0.617021 (4425 3825);
PAINT SKYBLUE (4425 3825);
FORCEPROP 1 LAST VOLTAGE 50V
J 0
(4425 3775);
DISPLAY 0.617021 (4425 3775);
PAINT SKYBLUE (4425 3775);
FORCEPROP 1 LAST TOLERANCE 10%
J 0
(4425 3725);
DISPLAY 0.617021 (4425 3725);
PAINT SKYBLUE (4425 3725);
FORCEPROP 1 LAST MATERIAL X7R
J 0
(4425 3675);
DISPLAY 0.617021 (4425 3675);
PAINT SKYBLUE (4425 3675);
FORCEPROP 1 LAST PACK_TYPE 0402
J 0
(4425 3625);
DISPLAY 0.617021 (4425 3625);
PAINT SKYBLUE (4425 3625);
FORCEPROP 1 LAST LOCATION PC475
J 0
(4425 3875);
DISPLAY 0.617021 (4425 3875);
PAINT AQUA (4425 3875);
FORCEPROP 1 LASTPIN (4375 3875) $PN 1
J 0
(4385 3855);
DISPLAY 0.617021 (4385 3855);
PAINT MONO (4385 3855);
FORCEPROP 1 LASTPIN (4375 3675) $PN 2
J 0
(4385 3655);
DISPLAY 0.617021 (4385 3655);
PAINT MONO (4385 3655);
FORCEPROP 2 LAST CDS_LIB pure_quanta
J 0
(4375 3775);
DISPLAY INVISIBLE (4375 3775);
FORCEPROP 1 LAST PATH I66
J 0
(4425 3925);
DISPLAY 0.978723 (4425 3925);
PAINT WHITE (4425 3925);
DISPLAY INVISIBLE (4425 3925);
FORCEPROP 1 LAST LOCATION PC475
J 0
(4425 3925);
DISPLAY 1.021277 (4425 3925);
PAINT AQUA (4425 3925);
DISPLAY INVISIBLE (4425 3925);
FORCEPROP 0 LAST $SEC 1
J 0
(4425 3925);
DISPLAY 0.680851 (4425 3925);
PAINT MONO (4425 3925);
DISPLAY INVISIBLE (4425 3925);
FORCEPROP 0 LAST CDS_SEC 1
J 0
(4425 3925);
DISPLAY 1.021277 (4425 3925);
DISPLAY INVISIBLE (4425 3925);
FORCEADD Q_RES..2
(5100 3750);
FORCEPROP 1 LAST PART_NUMBER CS31002FB08
J 0
(5140 3625);
DISPLAY 0.617021 (5140 3625);
PAINT BLUE (5140 3625);
DISPLAY INVISIBLE (5140 3625);
FORCEPROP 1 LAST TOLERANCE 1%
J 0
(5145 3775);
DISPLAY 0.617021 (5145 3775);
PAINT SKYBLUE (5145 3775);
FORCEPROP 1 LAST PACK_TYPE 0402LF
J 0
(5140 3575);
DISPLAY 0.617021 (5140 3575);
PAINT SKYBLUE (5140 3575);
FORCEPROP 1 LAST VALUE 10K
J 0
(5145 3825);
DISPLAY 0.617021 (5145 3825);
PAINT SKYBLUE (5145 3825);
FORCEPROP 1 LAST MATERIAL EMPTY
J 0
(5140 3675);
DISPLAY 0.617021 (5140 3675);
PAINT RED (5140 3675);
FORCEPROP 1 LAST WATTAGE 1/16W
J 0
(5140 3725);
DISPLAY 0.617021 (5140 3725);
PAINT SKYBLUE (5140 3725);
FORCEPROP 1 LAST LOCATION PR665
J 0
(5145 3875);
DISPLAY 0.617021 (5145 3875);
PAINT AQUA (5145 3875);
FORCEPROP 2 LAST CDS_LIB pure_quanta
J 0
(5100 3750);
DISPLAY INVISIBLE (5100 3750);
FORCEPROP 1 LAST PATH I67
J 0
(5150 3925);
DISPLAY 0.978723 (5150 3925);
PAINT WHITE (5150 3925);
DISPLAY INVISIBLE (5150 3925);
FORCEPROP 0 LAST $SEC 1
J 0
(5150 3925);
DISPLAY INVISIBLE (5150 3925);
FORCEPROP 0 LAST CDS_SEC 1
J 0
(5150 3925);
DISPLAY INVISIBLE (5150 3925);
FORCEPROP 1 LASTPIN (5100 3850) $PN 1
J 0
(5105 3812);
DISPLAY 0.787234 (5105 3812);
PAINT MONO (5105 3812);
DISPLAY INVISIBLE (5105 3812);
FORCEPROP 1 LASTPIN (5100 3650) $PN 2
J 0
(5105 3660);
DISPLAY 0.787234 (5105 3660);
PAINT MONO (5105 3660);
DISPLAY INVISIBLE (5105 3660);
FORCEADD UNIVERSAL_GND..1
(5100 3500);
FORCEPROP 3 LASTPIN (5100 3550) SIG_NAME GND\g
J 0
(5110 3560);
DISPLAY 0.659574 (5110 3560);
PAINT MONO (5110 3560);
DISPLAY INVISIBLE (5110 3560);
FORCEPROP 1 LAST HDL_POWER GND
J 1
(5125 3425);
DISPLAY 0.872340 (5125 3425);
PAINT GREEN (5125 3425);
DISPLAY INVISIBLE (5125 3425);
FORCEPROP 2 LAST CDS_LIB logical_power
J 0
(5100 3500);
DISPLAY INVISIBLE (5100 3500);
FORCEPROP 1 LAST PATH I68
J 0
(5175 3500);
DISPLAY 0.872340 (5175 3500);
PAINT AQUA (5175 3500);
DISPLAY INVISIBLE (5175 3500);
FORCEADD Q_CAP..2
(4700 4400);
FORCEPROP 1 LAST PART_NUMBER TMP_QCH14706KB18
J 1
(5025 4450);
DISPLAY 0.617021 (5025 4450);
PAINT BLUE (5025 4450);
DISPLAY INVISIBLE (5025 4450);
FORCEPROP 1 LAST VOLTAGE 50V
J 0
(5050 4400);
DISPLAY 0.617021 (5050 4400);
PAINT SKYBLUE (5050 4400);
FORCEPROP 1 LAST MATERIAL X7R
J 0
(4975 4500);
DISPLAY 0.617021 (4975 4500);
PAINT SKYBLUE (4975 4500);
FORCEPROP 1 LAST TOLERANCE 10%
J 2
(4950 4500);
DISPLAY 0.617021 (4950 4500);
PAINT SKYBLUE (4950 4500);
FORCEPROP 1 LAST VALUE 470PF
J 2
(5025 4400);
DISPLAY 0.617021 (5025 4400);
PAINT SKYBLUE (5025 4400);
FORCEPROP 1 LAST PACK_TYPE 0402
J 1
(5225 4400);
DISPLAY 0.617021 (5225 4400);
PAINT SKYBLUE (5225 4400);
FORCEPROP 1 LAST LOCATION PC1292
J 1
(4475 4400);
DISPLAY 0.617021 (4475 4400);
PAINT AQUA (4475 4400);
FORCEPROP 1 LASTPIN (4600 4400) $PN 1
J 0
(4590 4415);
DISPLAY 0.617021 (4590 4415);
FORCEPROP 1 LASTPIN (4800 4400) $PN 2
J 0
(4785 4415);
DISPLAY 0.617021 (4785 4415);
FORCEPROP 2 LAST CDS_LIB pure_quanta
J 0
(4700 4400);
PAINT MONO (4700 4400);
DISPLAY INVISIBLE (4700 4400);
FORCEPROP 1 LAST PATH I69
J 0
(4700 4600);
DISPLAY 0.978723 (4700 4600);
PAINT WHITE (4700 4600);
DISPLAY INVISIBLE (4700 4600);
FORCEPROP 2 LAST $SEC 1
J 0
(4700 4650);
DISPLAY 0.680851 (4700 4650);
PAINT MONO (4700 4650);
DISPLAY INVISIBLE (4700 4650);
FORCEPROP 2 LAST CDS_SEC 1
J 0
(4700 4650);
DISPLAY 1.021277 (4700 4650);
DISPLAY INVISIBLE (4700 4650);
FORCEADD OFFPAGE..5
(225 4900);
FORCEPROP 1 LAST COMMENT_BODY TRUE
J 0
(325 4825);
DISPLAY 0.872340 (325 4825);
PAINT GREEN (325 4825);
DISPLAY INVISIBLE (325 4825);
FORCEPROP 1 LAST OFFPAGE TRUE
J 0
(550 4775);
DISPLAY 0.872340 (550 4775);
PAINT GREEN (550 4775);
DISPLAY INVISIBLE (550 4775);
FORCEPROP 2 LAST CDS_LIB standard
J 0
(225 4900);
DISPLAY INVISIBLE (225 4900);
FORCEPROP 2 LAST PATH I7
J 0
(275 4975);
DISPLAY 1.021277 (275 4975);
DISPLAY INVISIBLE (275 4975);
FORCEADD Q_RES..1
(5675 4650);
FORCEPROP 1 LAST PART_NUMBER CS00002JB13
J 0
(5775 4725);
DISPLAY 0.617021 (5775 4725);
PAINT BLUE (5775 4725);
DISPLAY INVISIBLE (5775 4725);
FORCEPROP 1 LAST VALUE 0
J 2
(5825 4650);
DISPLAY 0.617021 (5825 4650);
PAINT SKYBLUE (5825 4650);
FORCEPROP 1 LAST TOLERANCE 5%
J 0
(5850 4650);
DISPLAY 0.617021 (5850 4650);
PAINT SKYBLUE (5850 4650);
FORCEPROP 1 LAST WATTAGE 1/16W
J 2
(6125 4775);
DISPLAY 0.617021 (6125 4775);
PAINT SKYBLUE (6125 4775);
FORCEPROP 1 LAST MATERIAL CHIP
J 0
(5925 4650);
DISPLAY 0.617021 (5925 4650);
PAINT SKYBLUE (5925 4650);
FORCEPROP 1 LAST PACK_TYPE 0402LF
J 0
(5775 4775);
DISPLAY 0.617021 (5775 4775);
PAINT SKYBLUE (5775 4775);
FORCEPROP 1 LAST LOCATION R2574
J 0
(5425 4650);
DISPLAY 0.617021 (5425 4650);
PAINT AQUA (5425 4650);
FORCEPROP 1 LASTPIN (5575 4650) $PN 1
J 0
(5587 4662);
DISPLAY 0.787234 (5587 4662);
PAINT MONO (5587 4662);
FORCEPROP 1 LASTPIN (5775 4650) $PN 2
J 0
(5737 4662);
DISPLAY 0.787234 (5737 4662);
PAINT MONO (5737 4662);
FORCEPROP 2 LAST CDS_LIB pure_quanta
J 0
(5675 4650);
DISPLAY INVISIBLE (5675 4650);
FORCEPROP 1 LAST PATH I70
J 0
(5625 4800);
DISPLAY 0.978723 (5625 4800);
PAINT WHITE (5625 4800);
DISPLAY INVISIBLE (5625 4800);
FORCEPROP 0 LAST $SEC 1
J 0
(5850 4775);
DISPLAY 0.680851 (5850 4775);
PAINT MONO (5850 4775);
DISPLAY INVISIBLE (5850 4775);
FORCEPROP 0 LAST CDS_SEC 1
J 0
(5850 4775);
DISPLAY 1.021277 (5850 4775);
DISPLAY INVISIBLE (5850 4775);
FORCEADD UNIVERSAL_GND..1
R 1
(5425 4400);
FORCEPROP 3 LASTPIN (5375 4400) SIG_NAME GND\g
J 0
(5385 4410);
DISPLAY 0.659574 (5385 4410);
PAINT MONO (5385 4410);
DISPLAY INVISIBLE (5385 4410);
FORCEPROP 1 LAST HDL_POWER GND
R 1
J 1
(5500 4425);
DISPLAY 0.872340 (5500 4425);
PAINT GREEN (5500 4425);
DISPLAY INVISIBLE (5500 4425);
FORCEPROP 2 LAST CDS_LIB logical_power
J 0
(5425 4400);
PAINT MONO (5425 4400);
DISPLAY INVISIBLE (5425 4400);
FORCEPROP 1 LAST PATH I71
R 1
J 0
(5425 4475);
DISPLAY 0.872340 (5425 4475);
PAINT AQUA (5425 4475);
DISPLAY INVISIBLE (5425 4475);
FORCEADD OFFPAGE..4
(6275 3950);
FORCEPROP 2 LAST $XR0 293 
J 0
(6461 3950);
DISPLAY 0.638298 (6461 3950);
PAINT MONO (6461 3950);
FORCEPROP 1 LAST COMMENT_BODY TRUE
J 0
(6250 3850);
DISPLAY 0.872340 (6250 3850);
PAINT GREEN (6250 3850);
DISPLAY INVISIBLE (6250 3850);
FORCEPROP 1 LAST OFFPAGE TRUE
J 0
(6600 3825);
DISPLAY 0.872340 (6600 3825);
PAINT GREEN (6600 3825);
DISPLAY INVISIBLE (6600 3825);
FORCEPROP 2 LAST CDS_LIB standard
J 0
(6275 3950);
DISPLAY INVISIBLE (6275 3950);
FORCEPROP 2 LAST PATH I72
J 0
(6475 4000);
DISPLAY 1.021277 (6475 4000);
DISPLAY INVISIBLE (6475 4000);
FORCEADD Q_RES..2
(6275 4900);
FORCEPROP 1 LAST PART_NUMBER CS21002FB06
J 0
(6300 4775);
DISPLAY 0.617021 (6300 4775);
PAINT BLUE (6300 4775);
DISPLAY INVISIBLE (6300 4775);
FORCEPROP 1 LAST WATTAGE 1/16W
J 0
(6300 4875);
DISPLAY 0.617021 (6300 4875);
PAINT SKYBLUE (6300 4875);
FORCEPROP 1 LAST TOLERANCE 1%
J 0
(6305 4925);
DISPLAY 0.617021 (6305 4925);
PAINT SKYBLUE (6305 4925);
FORCEPROP 1 LAST VALUE 1K
J 0
(6305 4975);
DISPLAY 0.617021 (6305 4975);
PAINT SKYBLUE (6305 4975);
FORCEPROP 1 LAST PACK_TYPE 0402LF
J 0
(6300 4725);
DISPLAY 0.617021 (6300 4725);
PAINT SKYBLUE (6300 4725);
FORCEPROP 1 LAST MATERIAL CHIP
J 0
(6300 4825);
DISPLAY 0.617021 (6300 4825);
PAINT RED (6300 4825);
FORCEPROP 1 LAST LOCATION R2573
J 0
(6305 5025);
DISPLAY 0.617021 (6305 5025);
PAINT AQUA (6305 5025);
FORCEPROP 1 LASTPIN (6275 5000) $PN 1
J 0
(6280 4962);
DISPLAY 0.617021 (6280 4962);
PAINT MONO (6280 4962);
FORCEPROP 1 LASTPIN (6275 4800) $PN 2
J 0
(6280 4810);
DISPLAY 0.617021 (6280 4810);
PAINT MONO (6280 4810);
FORCEPROP 1 LAST PATH I73
J 0
(6325 5075);
DISPLAY 0.978723 (6325 5075);
PAINT WHITE (6325 5075);
DISPLAY INVISIBLE (6325 5075);
FORCEPROP 2 LAST CDS_LIB pure_quanta
J 0
(6275 4900);
DISPLAY INVISIBLE (6275 4900);
FORCEPROP 1 LAST LOCATION R2573
J 0
(6325 5075);
DISPLAY 1.021277 (6325 5075);
PAINT AQUA (6325 5075);
DISPLAY INVISIBLE (6325 5075);
FORCEPROP 0 LAST $SEC 1
J 0
(6325 5075);
DISPLAY 0.680851 (6325 5075);
PAINT MONO (6325 5075);
DISPLAY INVISIBLE (6325 5075);
FORCEPROP 0 LAST CDS_SEC 1
J 0
(6325 5075);
DISPLAY 1.021277 (6325 5075);
DISPLAY INVISIBLE (6325 5075);
FORCEADD UNIVERSAL_GND..1
(6700 3800);
FORCEPROP 3 LASTPIN (6700 3850) SIG_NAME GND\g
J 0
(6710 3860);
DISPLAY 0.659574 (6710 3860);
PAINT MONO (6710 3860);
DISPLAY INVISIBLE (6710 3860);
FORCEPROP 1 LAST HDL_POWER GND
J 1
(6725 3725);
DISPLAY 0.872340 (6725 3725);
PAINT GREEN (6725 3725);
DISPLAY INVISIBLE (6725 3725);
FORCEPROP 2 LAST CDS_LIB logical_power
J 0
(6700 3800);
DISPLAY INVISIBLE (6700 3800);
FORCEPROP 1 LAST PATH I74
J 0
(6775 3800);
DISPLAY 0.872340 (6775 3800);
PAINT AQUA (6775 3800);
DISPLAY INVISIBLE (6775 3800);
FORCEADD Q_RES..2
(6700 4050);
FORCEPROP 1 LAST PART_NUMBER CS31002FB08
J 0
(6740 3925);
DISPLAY 0.617021 (6740 3925);
PAINT BLUE (6740 3925);
DISPLAY INVISIBLE (6740 3925);
FORCEPROP 1 LAST WATTAGE 1/16W
J 0
(6740 4025);
DISPLAY 0.617021 (6740 4025);
PAINT SKYBLUE (6740 4025);
FORCEPROP 1 LAST MATERIAL EMPTY
J 0
(6740 3975);
DISPLAY 0.617021 (6740 3975);
PAINT RED (6740 3975);
FORCEPROP 1 LAST TOLERANCE 1%
J 0
(6745 4075);
DISPLAY 0.617021 (6745 4075);
PAINT SKYBLUE (6745 4075);
FORCEPROP 1 LAST VALUE 10K
J 0
(6745 4125);
DISPLAY 0.617021 (6745 4125);
PAINT SKYBLUE (6745 4125);
FORCEPROP 1 LAST PACK_TYPE 0402LF
J 0
(6740 3875);
DISPLAY 0.617021 (6740 3875);
PAINT SKYBLUE (6740 3875);
FORCEPROP 1 LAST LOCATION PR667
J 0
(6745 4175);
DISPLAY 0.617021 (6745 4175);
PAINT AQUA (6745 4175);
FORCEPROP 2 LAST CDS_LIB pure_quanta
J 0
(6700 4050);
DISPLAY INVISIBLE (6700 4050);
FORCEPROP 1 LAST PATH I75
J 0
(6750 4225);
DISPLAY 0.978723 (6750 4225);
PAINT WHITE (6750 4225);
DISPLAY INVISIBLE (6750 4225);
FORCEPROP 0 LAST $SEC 1
J 0
(6750 4225);
DISPLAY INVISIBLE (6750 4225);
FORCEPROP 0 LAST CDS_SEC 1
J 0
(6750 4225);
DISPLAY INVISIBLE (6750 4225);
FORCEPROP 1 LASTPIN (6700 4150) $PN 1
J 0
(6705 4112);
DISPLAY 0.787234 (6705 4112);
PAINT MONO (6705 4112);
DISPLAY INVISIBLE (6705 4112);
FORCEPROP 1 LASTPIN (6700 3950) $PN 2
J 0
(6705 3960);
DISPLAY 0.787234 (6705 3960);
PAINT MONO (6705 3960);
DISPLAY INVISIBLE (6705 3960);
FORCEADD OFFPAGE..4
(7050 4250);
FORCEPROP 2 LAST $XR0 294 
J 0
(7236 4250);
DISPLAY 0.638298 (7236 4250);
PAINT MONO (7236 4250);
FORCEPROP 1 LAST COMMENT_BODY TRUE
J 0
(7025 4150);
DISPLAY 0.872340 (7025 4150);
PAINT GREEN (7025 4150);
DISPLAY INVISIBLE (7025 4150);
FORCEPROP 1 LAST OFFPAGE TRUE
J 0
(7375 4125);
DISPLAY 0.872340 (7375 4125);
PAINT GREEN (7375 4125);
DISPLAY INVISIBLE (7375 4125);
FORCEPROP 2 LAST CDS_LIB standard
J 0
(7050 4250);
DISPLAY INVISIBLE (7050 4250);
FORCEPROP 2 LAST PATH I76
J 0
(7250 4300);
DISPLAY 1.021277 (7250 4300);
DISPLAY INVISIBLE (7250 4300);
FORCEADD OFFPAGE..2
(7050 4650);
FORCEPROP 2 LAST $XR0 214 
J 0
(7239 4650);
DISPLAY 0.638298 (7239 4650);
PAINT MONO (7239 4650);
FORCEPROP 1 LAST COMMENT_BODY TRUE
J 0
(7005 4555);
DISPLAY 0.872340 (7005 4555);
PAINT GREEN (7005 4555);
DISPLAY INVISIBLE (7005 4555);
FORCEPROP 1 LAST OFFPAGE TRUE
J 0
(7375 4525);
DISPLAY 0.872340 (7375 4525);
PAINT GREEN (7375 4525);
DISPLAY INVISIBLE (7375 4525);
FORCEPROP 2 LAST CDS_LIB standard
J 0
(7050 4650);
DISPLAY INVISIBLE (7050 4650);
FORCEPROP 2 LAST PATH I77
J 0
(7375 4700);
DISPLAY 1.021277 (7375 4700);
DISPLAY INVISIBLE (7375 4700);
FORCEADD Q_RES..1
(5350 5350);
FORCEPROP 1 LAST PART_NUMBER CS00002JB13
J 0
(5450 5300);
DISPLAY 0.638298 (5450 5300);
DISPLAY INVISIBLE (5450 5300);
FORCEPROP 1 LAST PACK_TYPE 0402LF
J 0
(5575 5350);
DISPLAY 0.638298 (5575 5350);
FORCEPROP 1 LAST TOLERANCE 5%
J 0
(5500 5350);
DISPLAY 0.638298 (5500 5350);
FORCEPROP 1 LAST MATERIAL CHIP
J 0
(5150 5300);
DISPLAY 0.638298 (5150 5300);
FORCEPROP 1 LAST WATTAGE 1/16W
J 2
(5925 5350);
DISPLAY 0.638298 (5925 5350);
FORCEPROP 1 LAST VALUE 0
J 2
(5475 5350);
DISPLAY 0.638298 (5475 5350);
FORCEPROP 1 LAST LOCATION PR4246
J 0
(5100 5350);
DISPLAY 0.787234 (5100 5350);
FORCEPROP 1 LASTPIN (5250 5350) $PN 1
J 0
(5262 5362);
DISPLAY 0.787234 (5262 5362);
PAINT MONO (5262 5362);
FORCEPROP 1 LASTPIN (5450 5350) $PN 2
J 0
(5412 5362);
DISPLAY 0.787234 (5412 5362);
PAINT MONO (5412 5362);
FORCEPROP 2 LAST CDS_LIB pure_quanta
J 0
(5350 5350);
DISPLAY INVISIBLE (5350 5350);
FORCEPROP 1 LAST PATH I78
J 0
(5300 5500);
DISPLAY 0.978723 (5300 5500);
PAINT WHITE (5300 5500);
DISPLAY INVISIBLE (5300 5500);
FORCEPROP 0 LAST $SEC 1
J 0
(5925 5400);
DISPLAY 0.680851 (5925 5400);
PAINT MONO (5925 5400);
DISPLAY INVISIBLE (5925 5400);
FORCEPROP 0 LAST CDS_SEC 1
J 0
(5925 5400);
DISPLAY 1.021277 (5925 5400);
DISPLAY INVISIBLE (5925 5400);
FORCEADD Q_RES..1
(5350 5800);
FORCEPROP 1 LAST PART_NUMBER CS00002JB13
J 0
(5475 5850);
DISPLAY 0.617021 (5475 5850);
PAINT BLUE (5475 5850);
DISPLAY INVISIBLE (5475 5850);
FORCEPROP 1 LAST VALUE 0
J 2
(5500 5800);
DISPLAY 0.617021 (5500 5800);
PAINT SKYBLUE (5500 5800);
FORCEPROP 1 LAST TOLERANCE 5%
J 0
(5525 5800);
DISPLAY 0.617021 (5525 5800);
PAINT SKYBLUE (5525 5800);
FORCEPROP 1 LAST MATERIAL CHIP
J 0
(5600 5800);
DISPLAY 0.617021 (5600 5800);
PAINT SKYBLUE (5600 5800);
FORCEPROP 1 LAST LOCATION PR4245
J 0
(5100 5800);
DISPLAY 0.723404 (5100 5800);
PAINT AQUA (5100 5800);
FORCEPROP 1 LASTPIN (5250 5800) $PN 1
J 0
(5262 5812);
DISPLAY 0.787234 (5262 5812);
PAINT MONO (5262 5812);
FORCEPROP 1 LASTPIN (5450 5800) $PN 2
J 0
(5412 5812);
DISPLAY 0.787234 (5412 5812);
PAINT MONO (5412 5812);
FORCEPROP 1 LAST PACK_TYPE 0402LF
J 0
(5300 5900);
DISPLAY 0.404255 (5300 5900);
PAINT SKYBLUE (5300 5900);
DISPLAY INVISIBLE (5300 5900);
FORCEPROP 1 LAST WATTAGE 1/16W
J 2
(5525 5875);
DISPLAY 0.404255 (5525 5875);
PAINT SKYBLUE (5525 5875);
DISPLAY INVISIBLE (5525 5875);
FORCEPROP 2 LAST CDS_LIB pure_quanta
J 0
(5350 5800);
DISPLAY INVISIBLE (5350 5800);
FORCEPROP 1 LAST PATH I79
J 0
(5300 5950);
DISPLAY 0.978723 (5300 5950);
PAINT WHITE (5300 5950);
DISPLAY INVISIBLE (5300 5950);
FORCEPROP 0 LAST $SEC 1
J 0
(5475 5900);
DISPLAY 0.680851 (5475 5900);
PAINT MONO (5475 5900);
DISPLAY INVISIBLE (5475 5900);
FORCEPROP 0 LAST CDS_SEC 1
J 0
(5475 5900);
DISPLAY 1.021277 (5475 5900);
DISPLAY INVISIBLE (5475 5900);
FORCEADD OFFPAGE..1
(-725 7150);
FORCEPROP 2 LAST $XR0 47 
J 0
(-1006 7150);
DISPLAY 0.638298 (-1006 7150);
PAINT MONO (-1006 7150);
FORCEPROP 1 LAST COMMENT_BODY TRUE
J 0
(-600 7050);
DISPLAY 0.872340 (-600 7050);
PAINT GREEN (-600 7050);
DISPLAY INVISIBLE (-600 7050);
FORCEPROP 1 LAST OFFPAGE TRUE
J 0
(-400 7025);
DISPLAY 0.872340 (-400 7025);
PAINT GREEN (-400 7025);
DISPLAY INVISIBLE (-400 7025);
FORCEPROP 2 LAST CDS_LIB standard
J 0
(-725 7150);
DISPLAY INVISIBLE (-725 7150);
FORCEPROP 2 LAST PATH I8
J 0
(-1000 7200);
DISPLAY 1.021277 (-1000 7200);
DISPLAY INVISIBLE (-1000 7200);
FORCEADD Q_RES..1
(5350 6250);
FORCEPROP 1 LAST PART_NUMBER CS00002JB13
J 0
(5450 6200);
DISPLAY 0.638298 (5450 6200);
DISPLAY INVISIBLE (5450 6200);
FORCEPROP 1 LAST WATTAGE 1/16W
J 2
(5925 6250);
DISPLAY 0.638298 (5925 6250);
FORCEPROP 1 LAST PACK_TYPE 0402LF
J 0
(5575 6250);
DISPLAY 0.638298 (5575 6250);
FORCEPROP 1 LAST VALUE 0
J 2
(5475 6250);
DISPLAY 0.638298 (5475 6250);
FORCEPROP 1 LAST MATERIAL CHIP
J 0
(5150 6200);
DISPLAY 0.638298 (5150 6200);
FORCEPROP 1 LAST TOLERANCE 5%
J 0
(5500 6250);
DISPLAY 0.638298 (5500 6250);
FORCEPROP 1 LAST LOCATION PR4244
J 0
(5125 6225);
DISPLAY 0.787234 (5125 6225);
FORCEPROP 1 LASTPIN (5250 6250) $PN 1
J 0
(5262 6262);
DISPLAY 0.787234 (5262 6262);
PAINT MONO (5262 6262);
FORCEPROP 1 LASTPIN (5450 6250) $PN 2
J 0
(5412 6262);
DISPLAY 0.787234 (5412 6262);
PAINT MONO (5412 6262);
FORCEPROP 2 LAST CDS_LIB pure_quanta
J 0
(5350 6250);
DISPLAY INVISIBLE (5350 6250);
FORCEPROP 1 LAST PATH I80
J 0
(5300 6400);
DISPLAY 0.978723 (5300 6400);
PAINT WHITE (5300 6400);
DISPLAY INVISIBLE (5300 6400);
FORCEPROP 0 LAST $SEC 1
J 0
(5925 6300);
DISPLAY 0.680851 (5925 6300);
PAINT MONO (5925 6300);
DISPLAY INVISIBLE (5925 6300);
FORCEPROP 0 LAST CDS_SEC 1
J 0
(5925 6300);
DISPLAY 1.021277 (5925 6300);
DISPLAY INVISIBLE (5925 6300);
FORCEADD Q_RES..1
(5350 6700);
FORCEPROP 1 LAST PART_NUMBER CS00002JB13
J 0
(5450 6650);
DISPLAY 0.638298 (5450 6650);
DISPLAY INVISIBLE (5450 6650);
FORCEPROP 1 LAST PACK_TYPE 0402LF
J 0
(5575 6700);
DISPLAY 0.638298 (5575 6700);
FORCEPROP 1 LAST WATTAGE 1/16W
J 2
(5925 6700);
DISPLAY 0.638298 (5925 6700);
FORCEPROP 1 LAST TOLERANCE 5%
J 0
(5500 6700);
DISPLAY 0.638298 (5500 6700);
FORCEPROP 1 LAST VALUE 0
J 2
(5475 6700);
DISPLAY 0.638298 (5475 6700);
FORCEPROP 1 LAST MATERIAL CHIP
J 0
(5150 6650);
DISPLAY 0.638298 (5150 6650);
FORCEPROP 1 LAST LOCATION PR4243
J 0
(5125 6700);
DISPLAY 0.638298 (5125 6700);
FORCEPROP 1 LASTPIN (5250 6700) $PN 1
J 0
(5262 6712);
DISPLAY 0.787234 (5262 6712);
PAINT MONO (5262 6712);
FORCEPROP 1 LASTPIN (5450 6700) $PN 2
J 0
(5412 6712);
DISPLAY 0.787234 (5412 6712);
PAINT MONO (5412 6712);
FORCEPROP 2 LAST CDS_LIB pure_quanta
J 0
(5350 6700);
DISPLAY INVISIBLE (5350 6700);
FORCEPROP 1 LAST PATH I81
J 0
(5300 6850);
DISPLAY 0.978723 (5300 6850);
PAINT WHITE (5300 6850);
DISPLAY INVISIBLE (5300 6850);
FORCEPROP 0 LAST $SEC 1
J 0
(5925 6750);
DISPLAY 0.680851 (5925 6750);
PAINT MONO (5925 6750);
DISPLAY INVISIBLE (5925 6750);
FORCEPROP 0 LAST CDS_SEC 1
J 0
(5925 6750);
DISPLAY 1.021277 (5925 6750);
DISPLAY INVISIBLE (5925 6750);
FORCEADD OFFPAGE..4
(5400 4900);
FORCEPROP 2 LAST $XR0 294 
J 0
(5586 4900);
DISPLAY 0.638298 (5586 4900);
PAINT MONO (5586 4900);
FORCEPROP 1 LAST COMMENT_BODY TRUE
J 0
(5375 4800);
DISPLAY 0.872340 (5375 4800);
PAINT GREEN (5375 4800);
DISPLAY INVISIBLE (5375 4800);
FORCEPROP 1 LAST OFFPAGE TRUE
J 0
(5725 4775);
DISPLAY 0.872340 (5725 4775);
PAINT GREEN (5725 4775);
DISPLAY INVISIBLE (5725 4775);
FORCEPROP 2 LAST CDS_LIB standard
J 0
(5400 4900);
DISPLAY INVISIBLE (5400 4900);
FORCEPROP 2 LAST PATH I82
J 0
(5600 4950);
DISPLAY 1.021277 (5600 4950);
DISPLAY INVISIBLE (5600 4950);
FORCEADD OFFPAGE..2
(5400 5000);
FORCEPROP 2 LAST $XR0 294 
J 0
(5589 5000);
DISPLAY 0.638298 (5589 5000);
PAINT MONO (5589 5000);
FORCEPROP 1 LAST COMMENT_BODY TRUE
J 0
(5355 4905);
DISPLAY 0.872340 (5355 4905);
PAINT GREEN (5355 4905);
DISPLAY INVISIBLE (5355 4905);
FORCEPROP 1 LAST OFFPAGE TRUE
J 0
(5725 4875);
DISPLAY 0.872340 (5725 4875);
PAINT GREEN (5725 4875);
DISPLAY INVISIBLE (5725 4875);
FORCEPROP 2 LAST CDS_LIB standard
J 0
(5400 5000);
DISPLAY INVISIBLE (5400 5000);
FORCEPROP 2 LAST PATH I83
J 0
(5600 5050);
DISPLAY 1.021277 (5600 5050);
DISPLAY INVISIBLE (5600 5050);
FORCEADD UNIVERSAL_GND..1
(5975 5275);
FORCEPROP 3 LASTPIN (5975 5325) SIG_NAME GND\g
J 0
(5985 5335);
DISPLAY 0.659574 (5985 5335);
PAINT MONO (5985 5335);
DISPLAY INVISIBLE (5985 5335);
FORCEPROP 1 LAST HDL_POWER GND
J 1
(6000 5200);
DISPLAY 0.872340 (6000 5200);
PAINT GREEN (6000 5200);
DISPLAY INVISIBLE (6000 5200);
FORCEPROP 2 LAST CDS_LIB logical_power
J 0
(5975 5275);
DISPLAY INVISIBLE (5975 5275);
FORCEPROP 1 LAST PATH I84
J 0
(6050 5275);
DISPLAY 0.872340 (6050 5275);
PAINT AQUA (6050 5275);
DISPLAY INVISIBLE (6050 5275);
FORCEADD VCC15..1
(6275 5150);
FORCEPROP 3 LASTPIN (6275 5100) SIG_NAME P3V3_AUX\g
J 0
(6285 5110);
DISPLAY 0.659574 (6285 5110);
PAINT MONO (6285 5110);
DISPLAY INVISIBLE (6285 5110);
FORCEPROP 1 LAST HDL_POWER P3V3_AUX
J 1
(6275 5200);
DISPLAY 0.617021 (6275 5200);
PAINT GREEN (6275 5200);
FORCEPROP 2 LAST CDS_LIB logical_power
J 0
(6275 5150);
DISPLAY INVISIBLE (6275 5150);
FORCEPROP 1 LAST PATH I85
J 0
(6325 5175);
DISPLAY 0.872340 (6325 5175);
PAINT AQUA (6325 5175);
DISPLAY INVISIBLE (6325 5175);
FORCEADD UNIVERSAL_GND..1
(5975 5725);
FORCEPROP 3 LASTPIN (5975 5775) SIG_NAME GND\g
J 0
(5985 5785);
DISPLAY 0.659574 (5985 5785);
PAINT MONO (5985 5785);
DISPLAY INVISIBLE (5985 5785);
FORCEPROP 1 LAST HDL_POWER GND
J 1
(6000 5650);
DISPLAY 0.872340 (6000 5650);
PAINT GREEN (6000 5650);
DISPLAY INVISIBLE (6000 5650);
FORCEPROP 2 LAST CDS_LIB logical_power
J 0
(5975 5725);
DISPLAY INVISIBLE (5975 5725);
FORCEPROP 1 LAST PATH I86
J 0
(6050 5725);
DISPLAY 0.872340 (6050 5725);
PAINT AQUA (6050 5725);
DISPLAY INVISIBLE (6050 5725);
FORCEADD UNIVERSAL_GND..1
(5975 6175);
FORCEPROP 3 LASTPIN (5975 6225) SIG_NAME GND\g
J 0
(5985 6235);
DISPLAY 0.659574 (5985 6235);
PAINT MONO (5985 6235);
DISPLAY INVISIBLE (5985 6235);
FORCEPROP 1 LAST HDL_POWER GND
J 1
(6000 6100);
DISPLAY 0.872340 (6000 6100);
PAINT GREEN (6000 6100);
DISPLAY INVISIBLE (6000 6100);
FORCEPROP 2 LAST CDS_LIB logical_power
J 0
(5975 6175);
DISPLAY INVISIBLE (5975 6175);
FORCEPROP 1 LAST PATH I87
J 0
(6050 6175);
DISPLAY 0.872340 (6050 6175);
PAINT AQUA (6050 6175);
DISPLAY INVISIBLE (6050 6175);
FORCEADD UNIVERSAL_GND..1
(5975 6625);
FORCEPROP 3 LASTPIN (5975 6675) SIG_NAME GND\g
J 0
(5985 6685);
DISPLAY 0.659574 (5985 6685);
PAINT MONO (5985 6685);
DISPLAY INVISIBLE (5985 6685);
FORCEPROP 1 LAST HDL_POWER GND
J 1
(6000 6550);
DISPLAY 0.872340 (6000 6550);
PAINT GREEN (6000 6550);
DISPLAY INVISIBLE (6000 6550);
FORCEPROP 2 LAST CDS_LIB logical_power
J 0
(5975 6625);
DISPLAY INVISIBLE (5975 6625);
FORCEPROP 1 LAST PATH I88
J 0
(6050 6625);
DISPLAY 0.872340 (6050 6625);
PAINT AQUA (6050 6625);
DISPLAY INVISIBLE (6050 6625);
FORCEADD Q_RES..1
(5350 7150);
FORCEPROP 1 LAST PART_NUMBER CS00002JB13
J 0
(5450 7100);
DISPLAY 0.638298 (5450 7100);
DISPLAY INVISIBLE (5450 7100);
FORCEPROP 1 LAST WATTAGE 1/16W
J 2
(5925 7150);
DISPLAY 0.638298 (5925 7150);
FORCEPROP 1 LAST TOLERANCE 5%
J 0
(5500 7150);
DISPLAY 0.638298 (5500 7150);
FORCEPROP 1 LAST VALUE 0
J 2
(5475 7150);
DISPLAY 0.638298 (5475 7150);
FORCEPROP 1 LAST MATERIAL CHIP
J 0
(5150 7100);
DISPLAY 0.638298 (5150 7100);
FORCEPROP 1 LAST PACK_TYPE 0402LF
J 0
(5575 7150);
DISPLAY 0.638298 (5575 7150);
FORCEPROP 1 LAST LOCATION PR4242
J 0
(5100 7150);
DISPLAY 0.787234 (5100 7150);
FORCEPROP 1 LASTPIN (5250 7150) $PN 1
J 0
(5262 7162);
DISPLAY 0.787234 (5262 7162);
PAINT MONO (5262 7162);
FORCEPROP 1 LASTPIN (5450 7150) $PN 2
J 0
(5412 7162);
DISPLAY 0.787234 (5412 7162);
PAINT MONO (5412 7162);
FORCEPROP 2 LAST CDS_LIB pure_quanta
J 0
(5350 7150);
DISPLAY INVISIBLE (5350 7150);
FORCEPROP 1 LAST PATH I89
J 0
(5300 7300);
DISPLAY 0.978723 (5300 7300);
PAINT WHITE (5300 7300);
DISPLAY INVISIBLE (5300 7300);
FORCEPROP 0 LAST $SEC 1
J 0
(5925 7200);
DISPLAY 0.680851 (5925 7200);
PAINT MONO (5925 7200);
DISPLAY INVISIBLE (5925 7200);
FORCEPROP 0 LAST CDS_SEC 1
J 0
(5925 7200);
DISPLAY 1.021277 (5925 7200);
DISPLAY INVISIBLE (5925 7200);
FORCEADD OFFPAGE..6
(-175 7850);
FORCEPROP 2 LAST $XR1 296 
J 0
(-605 7850);
DISPLAY 0.638298 (-605 7850);
PAINT MONO (-605 7850);
FORCEPROP 2 LAST $XR0 241 
J 0
(-485 7850);
DISPLAY 0.638298 (-485 7850);
PAINT MONO (-485 7850);
FORCEPROP 1 LAST COMMENT_BODY TRUE
J 0
(-75 7775);
DISPLAY 0.872340 (-75 7775);
PAINT GREEN (-75 7775);
DISPLAY INVISIBLE (-75 7775);
FORCEPROP 1 LAST OFFPAGE TRUE
J 0
(150 7725);
DISPLAY 0.872340 (150 7725);
PAINT GREEN (150 7725);
DISPLAY INVISIBLE (150 7725);
FORCEPROP 2 LAST CDS_LIB standard
J 0
(-175 7850);
DISPLAY INVISIBLE (-175 7850);
FORCEPROP 2 LAST PATH I9
J 0
(-475 7900);
DISPLAY 1.021277 (-475 7900);
DISPLAY INVISIBLE (-475 7900);
FORCEADD OFFPAGE..4
(5375 7600);
FORCEPROP 2 LAST $XR0 293 
J 0
(5561 7600);
DISPLAY 0.638298 (5561 7600);
PAINT MONO (5561 7600);
FORCEPROP 1 LAST COMMENT_BODY TRUE
J 0
(5350 7500);
DISPLAY 0.872340 (5350 7500);
PAINT GREEN (5350 7500);
DISPLAY INVISIBLE (5350 7500);
FORCEPROP 1 LAST OFFPAGE TRUE
J 0
(5700 7475);
DISPLAY 0.872340 (5700 7475);
PAINT GREEN (5700 7475);
DISPLAY INVISIBLE (5700 7475);
FORCEPROP 2 LAST CDS_LIB standard
J 0
(5375 7600);
DISPLAY INVISIBLE (5375 7600);
FORCEPROP 2 LAST PATH I90
J 0
(5575 7650);
DISPLAY 1.021277 (5575 7650);
DISPLAY INVISIBLE (5575 7650);
FORCEADD OFFPAGE..2
(5375 7700);
FORCEPROP 2 LAST $XR0 293 
J 0
(5564 7700);
DISPLAY 0.638298 (5564 7700);
PAINT MONO (5564 7700);
FORCEPROP 1 LAST COMMENT_BODY TRUE
J 0
(5330 7605);
DISPLAY 0.872340 (5330 7605);
PAINT GREEN (5330 7605);
DISPLAY INVISIBLE (5330 7605);
FORCEPROP 1 LAST OFFPAGE TRUE
J 0
(5700 7575);
DISPLAY 0.872340 (5700 7575);
PAINT GREEN (5700 7575);
DISPLAY INVISIBLE (5700 7575);
FORCEPROP 2 LAST CDS_LIB standard
J 0
(5375 7700);
DISPLAY INVISIBLE (5375 7700);
FORCEPROP 2 LAST PATH I91
J 0
(5575 7750);
DISPLAY 1.021277 (5575 7750);
DISPLAY INVISIBLE (5575 7750);
FORCEADD Q_CAP..1
(4800 8475);
FORCEPROP 1 LAST PART_NUMBER CH6101MEB03
J 0
(4850 8300);
DISPLAY 0.617021 (4850 8300);
PAINT BLUE (4850 8300);
DISPLAY INVISIBLE (4850 8300);
FORCEPROP 1 LAST VOLTAGE 6.3V
J 0
(4850 8500);
DISPLAY 0.617021 (4850 8500);
PAINT SKYBLUE (4850 8500);
FORCEPROP 1 LAST VALUE 10UF
J 0
(4850 8550);
DISPLAY 0.617021 (4850 8550);
PAINT SKYBLUE (4850 8550);
FORCEPROP 1 LAST TOLERANCE 20%
J 0
(4850 8450);
DISPLAY 0.617021 (4850 8450);
PAINT SKYBLUE (4850 8450);
FORCEPROP 1 LAST MATERIAL X6S
J 0
(4850 8400);
DISPLAY 0.617021 (4850 8400);
PAINT SKYBLUE (4850 8400);
FORCEPROP 1 LAST PACK_TYPE C0402
J 0
(4850 8350);
DISPLAY 0.617021 (4850 8350);
PAINT SKYBLUE (4850 8350);
FORCEPROP 1 LAST LOCATION PC477
J 0
(4850 8600);
DISPLAY 0.617021 (4850 8600);
PAINT AQUA (4850 8600);
FORCEPROP 1 LASTPIN (4800 8575) $PN 1
J 0
(4810 8555);
DISPLAY 0.617021 (4810 8555);
PAINT MONO (4810 8555);
FORCEPROP 1 LASTPIN (4800 8375) $PN 2
J 0
(4810 8355);
DISPLAY 0.617021 (4810 8355);
PAINT MONO (4810 8355);
FORCEPROP 2 LAST CDS_LIB pure_quanta
J 0
(4800 8475);
DISPLAY INVISIBLE (4800 8475);
FORCEPROP 1 LAST PATH I92
J 0
(4850 8625);
DISPLAY 0.978723 (4850 8625);
PAINT WHITE (4850 8625);
DISPLAY INVISIBLE (4850 8625);
FORCEPROP 1 LAST LOCATION PC477
J 0
(4850 8650);
DISPLAY 1.021277 (4850 8650);
PAINT AQUA (4850 8650);
DISPLAY INVISIBLE (4850 8650);
FORCEPROP 0 LAST $SEC 1
J 0
(4850 8650);
DISPLAY 0.680851 (4850 8650);
PAINT MONO (4850 8650);
DISPLAY INVISIBLE (4850 8650);
FORCEPROP 0 LAST CDS_SEC 1
J 0
(4850 8650);
DISPLAY 1.021277 (4850 8650);
DISPLAY INVISIBLE (4850 8650);
FORCEADD Q_CAP..1
(4800 8950);
FORCEPROP 1 LAST PART_NUMBER CH4106K1B01
J 0
(4850 8775);
DISPLAY 0.617021 (4850 8775);
PAINT BLUE (4850 8775);
DISPLAY INVISIBLE (4850 8775);
FORCEPROP 1 LAST VALUE 100NF
J 0
(4850 9025);
DISPLAY 0.617021 (4850 9025);
PAINT SKYBLUE (4850 9025);
FORCEPROP 1 LAST MATERIAL EMPTY
J 0
(4850 8875);
DISPLAY 0.617021 (4850 8875);
PAINT RED (4850 8875);
FORCEPROP 1 LAST TOLERANCE 10%
J 0
(4850 8925);
DISPLAY 0.617021 (4850 8925);
PAINT SKYBLUE (4850 8925);
FORCEPROP 1 LAST VOLTAGE 50V
J 0
(4850 8975);
DISPLAY 0.617021 (4850 8975);
PAINT SKYBLUE (4850 8975);
FORCEPROP 1 LAST PACK_TYPE C0402
J 0
(4850 8825);
DISPLAY 0.617021 (4850 8825);
PAINT SKYBLUE (4850 8825);
FORCEPROP 1 LAST LOCATION PC476
J 0
(4850 9075);
DISPLAY 0.617021 (4850 9075);
PAINT AQUA (4850 9075);
FORCEPROP 1 LASTPIN (4800 9050) $PN 1
J 0
(4810 9030);
DISPLAY 0.617021 (4810 9030);
PAINT MONO (4810 9030);
FORCEPROP 1 LASTPIN (4800 8850) $PN 2
J 0
(4810 8830);
DISPLAY 0.617021 (4810 8830);
PAINT MONO (4810 8830);
FORCEPROP 2 LAST CDS_LIB pure_quanta
J 0
(4800 8950);
DISPLAY INVISIBLE (4800 8950);
FORCEPROP 1 LAST PATH I93
J 0
(4850 9100);
DISPLAY 0.978723 (4850 9100);
PAINT WHITE (4850 9100);
DISPLAY INVISIBLE (4850 9100);
FORCEPROP 1 LAST LOCATION PC476
J 0
(4850 9125);
DISPLAY 1.021277 (4850 9125);
PAINT AQUA (4850 9125);
DISPLAY INVISIBLE (4850 9125);
FORCEPROP 0 LAST $SEC 1
J 0
(4850 9125);
DISPLAY 0.680851 (4850 9125);
PAINT MONO (4850 9125);
DISPLAY INVISIBLE (4850 9125);
FORCEPROP 0 LAST CDS_SEC 1
J 0
(4850 9125);
DISPLAY 1.021277 (4850 9125);
DISPLAY INVISIBLE (4850 9125);
FORCEADD OFFPAGE..2
(5375 8150);
FORCEPROP 2 LAST $XR0 293 
J 0
(5564 8150);
DISPLAY 0.638298 (5564 8150);
PAINT MONO (5564 8150);
FORCEPROP 1 LAST COMMENT_BODY TRUE
J 0
(5330 8055);
DISPLAY 0.872340 (5330 8055);
PAINT GREEN (5330 8055);
DISPLAY INVISIBLE (5330 8055);
FORCEPROP 1 LAST OFFPAGE TRUE
J 0
(5700 8025);
DISPLAY 0.872340 (5700 8025);
PAINT GREEN (5700 8025);
DISPLAY INVISIBLE (5700 8025);
FORCEPROP 2 LAST CDS_LIB standard
J 0
(5375 8150);
DISPLAY INVISIBLE (5375 8150);
FORCEPROP 2 LAST PATH I94
J 0
(5575 8200);
DISPLAY 1.021277 (5575 8200);
DISPLAY INVISIBLE (5575 8200);
FORCEADD OFFPAGE..4
(5375 8050);
FORCEPROP 2 LAST $XR0 293 
J 0
(5561 8050);
DISPLAY 0.638298 (5561 8050);
PAINT MONO (5561 8050);
FORCEPROP 1 LAST COMMENT_BODY TRUE
J 0
(5350 7950);
DISPLAY 0.872340 (5350 7950);
PAINT GREEN (5350 7950);
DISPLAY INVISIBLE (5350 7950);
FORCEPROP 1 LAST OFFPAGE TRUE
J 0
(5700 7925);
DISPLAY 0.872340 (5700 7925);
PAINT GREEN (5700 7925);
DISPLAY INVISIBLE (5700 7925);
FORCEPROP 2 LAST CDS_LIB standard
J 0
(5375 8050);
DISPLAY INVISIBLE (5375 8050);
FORCEPROP 2 LAST PATH I95
J 0
(5575 8100);
DISPLAY 1.021277 (5575 8100);
DISPLAY INVISIBLE (5575 8100);
FORCEADD Q_CAP..1
(5200 8475);
FORCEPROP 1 LAST PART_NUMBER CH5103KEB01
J 0
(5250 8300);
DISPLAY 0.617021 (5250 8300);
PAINT BLUE (5250 8300);
DISPLAY INVISIBLE (5250 8300);
FORCEPROP 1 LAST PACK_TYPE C0402
J 0
(5250 8350);
DISPLAY 0.617021 (5250 8350);
PAINT SKYBLUE (5250 8350);
FORCEPROP 1 LAST VOLTAGE 16V
J 0
(5250 8500);
DISPLAY 0.617021 (5250 8500);
PAINT SKYBLUE (5250 8500);
FORCEPROP 1 LAST TOLERANCE 10%
J 0
(5250 8450);
DISPLAY 0.617021 (5250 8450);
PAINT SKYBLUE (5250 8450);
FORCEPROP 1 LAST MATERIAL X6S
J 0
(5250 8400);
DISPLAY 0.617021 (5250 8400);
PAINT SKYBLUE (5250 8400);
FORCEPROP 1 LAST VALUE 1UF
J 0
(5250 8550);
DISPLAY 0.617021 (5250 8550);
PAINT SKYBLUE (5250 8550);
FORCEPROP 1 LAST LOCATION PC1193
J 0
(5250 8600);
DISPLAY 0.617021 (5250 8600);
PAINT AQUA (5250 8600);
FORCEPROP 1 LASTPIN (5200 8575) $PN 1
J 0
(5210 8555);
DISPLAY 0.617021 (5210 8555);
FORCEPROP 1 LASTPIN (5200 8375) $PN 2
J 0
(5210 8355);
DISPLAY 0.617021 (5210 8355);
FORCEPROP 2 LAST CDS_LIB pure_quanta
J 0
(5200 8475);
PAINT MONO (5200 8475);
DISPLAY INVISIBLE (5200 8475);
FORCEPROP 1 LAST PATH I96
J 0
(5250 8625);
DISPLAY 0.978723 (5250 8625);
PAINT WHITE (5250 8625);
DISPLAY INVISIBLE (5250 8625);
FORCEPROP 2 LAST $SEC 1
J 0
(5250 8675);
DISPLAY 0.680851 (5250 8675);
PAINT MONO (5250 8675);
DISPLAY INVISIBLE (5250 8675);
FORCEPROP 2 LAST CDS_SEC 1
J 0
(5250 8675);
DISPLAY 1.021277 (5250 8675);
DISPLAY INVISIBLE (5250 8675);
FORCEADD Q_CAP..1
(5200 8950);
FORCEPROP 1 LAST PART_NUMBER CH5103KEB01
J 0
(5250 8775);
DISPLAY 0.617021 (5250 8775);
PAINT BLUE (5250 8775);
DISPLAY INVISIBLE (5250 8775);
FORCEPROP 1 LAST VOLTAGE 16V
J 0
(5250 8975);
DISPLAY 0.617021 (5250 8975);
PAINT SKYBLUE (5250 8975);
FORCEPROP 1 LAST TOLERANCE 10%
J 0
(5250 8925);
DISPLAY 0.617021 (5250 8925);
PAINT SKYBLUE (5250 8925);
FORCEPROP 1 LAST MATERIAL X6S
J 0
(5250 8875);
DISPLAY 0.617021 (5250 8875);
PAINT SKYBLUE (5250 8875);
FORCEPROP 1 LAST VALUE 1UF
J 0
(5250 9025);
DISPLAY 0.617021 (5250 9025);
PAINT SKYBLUE (5250 9025);
FORCEPROP 1 LAST PACK_TYPE C0402
J 0
(5250 8825);
DISPLAY 0.617021 (5250 8825);
PAINT SKYBLUE (5250 8825);
FORCEPROP 1 LAST LOCATION PC478
J 0
(5250 9075);
DISPLAY 0.617021 (5250 9075);
PAINT AQUA (5250 9075);
FORCEPROP 1 LASTPIN (5200 9050) $PN 1
J 0
(5210 9030);
DISPLAY 0.617021 (5210 9030);
PAINT MONO (5210 9030);
FORCEPROP 1 LASTPIN (5200 8850) $PN 2
J 0
(5210 8830);
DISPLAY 0.617021 (5210 8830);
PAINT MONO (5210 8830);
FORCEPROP 2 LAST CDS_LIB pure_quanta
J 0
(5200 8950);
DISPLAY INVISIBLE (5200 8950);
FORCEPROP 1 LAST PATH I97
J 0
(5250 9100);
DISPLAY 0.978723 (5250 9100);
PAINT WHITE (5250 9100);
DISPLAY INVISIBLE (5250 9100);
FORCEPROP 1 LAST LOCATION PC478
J 0
(5250 9125);
DISPLAY 1.021277 (5250 9125);
PAINT AQUA (5250 9125);
DISPLAY INVISIBLE (5250 9125);
FORCEPROP 0 LAST $SEC 1
J 0
(5250 9125);
DISPLAY 0.680851 (5250 9125);
PAINT MONO (5250 9125);
DISPLAY INVISIBLE (5250 9125);
FORCEPROP 0 LAST CDS_SEC 1
J 0
(5250 9125);
DISPLAY 1.021277 (5250 9125);
DISPLAY INVISIBLE (5250 9125);
FORCEADD UNIVERSAL_GND..1
(5975 7075);
FORCEPROP 3 LASTPIN (5975 7125) SIG_NAME GND\g
J 0
(5985 7135);
DISPLAY 0.659574 (5985 7135);
PAINT MONO (5985 7135);
DISPLAY INVISIBLE (5985 7135);
FORCEPROP 1 LAST HDL_POWER GND
J 1
(6000 7000);
DISPLAY 0.872340 (6000 7000);
PAINT GREEN (6000 7000);
DISPLAY INVISIBLE (6000 7000);
FORCEPROP 2 LAST CDS_LIB logical_power
J 0
(5975 7075);
DISPLAY INVISIBLE (5975 7075);
FORCEPROP 1 LAST PATH I98
J 0
(6050 7075);
DISPLAY 0.872340 (6050 7075);
PAINT AQUA (6050 7075);
DISPLAY INVISIBLE (6050 7075);
FORCEADD UNIVERSAL_GND..1
R 3
(5650 8275);
FORCEPROP 3 LASTPIN (5600 8275) SIG_NAME GND\g
J 0
(5610 8285);
DISPLAY 0.659574 (5610 8285);
PAINT MONO (5610 8285);
DISPLAY INVISIBLE (5610 8285);
FORCEPROP 1 LAST HDL_POWER GND
R 1
J 1
(5725 8250);
DISPLAY 0.872340 (5725 8250);
PAINT GREEN (5725 8250);
DISPLAY INVISIBLE (5725 8250);
FORCEPROP 2 LAST CDS_LIB logical_power
J 0
(5650 8275);
PAINT MONO (5650 8275);
DISPLAY INVISIBLE (5650 8275);
FORCEPROP 1 LAST PATH I99
R 1
J 2
(5650 8200);
DISPLAY 0.872340 (5650 8200);
PAINT AQUA (5650 8200);
DISPLAY INVISIBLE (5650 8200);
FORCEADD QUANTA_TITLE_BLOCK_C..1
(8100 2850);
FORCEPROP 0 LAST CDS_CON_LAST_MODIFIED Fri Aug 25 14:05:03 2023
J 0
(6215 2865);
DISPLAY INVISIBLE (6215 2865);
FORCEPROP 1 LAST CUSTOM_TXT_CDS <CON_LAST_MODIFIED>
J 0
(6215 2865);
DISPLAY 0.978723 (6215 2865);
FORCEPROP 2 LAST CUSTOM_TXT_CDS <XR_PAGE_TITLE>
J 0
(210 8100);
DISPLAY 0.638298 (210 8100);
PAINT PINK (210 8100);
DISPLAY INVISIBLE (210 8100);
FORCEPROP 1 LAST CUSTOM_TXT_CDS <NAME_2>
J 0
(4925 2900);
FORCEPROP 1 LAST CUSTOM_TXT_CDS <NAME_1>
J 0
(4925 3025);
FORCEPROP 1 LAST CUSTOM_TXT_CDS <Q_NUMBER>
J 0
(6697 2953);
DISPLAY 1.212766 (6697 2953);
FORCEPROP 1 LAST CUSTOM_TXT_CDS <Q_PROJ>
J 0
(5718 2952);
DISPLAY 1.212766 (5718 2952);
FORCEPROP 1 LAST CUSTOM_TXT_CDS <Q_REV>
J 0
(7916 2953);
DISPLAY 1.212766 (7916 2953);
FORCEPROP 1 LAST CUSTOM_TXT_CDS <CON_PAGE_NUM> OF <CON_TOTAL_PAGES>
J 0
(7654 2868);
DISPLAY 0.978723 (7654 2868);
FORCEPROP 1 LAST Q_TITLE VCCINFAON/VCCFA_EHV CPU1 VR CONTROLLER (1/3)
J 0
(-1200 2900);
DISPLAY 2.446809 (-1200 2900);
PAINT GREEN (-1200 2900);
FORCEPROP 1 LAST Q_DEPT 
J 1
(4337 2899);
DISPLAY 1.957447 (4337 2899);
PAINT GREEN (4337 2899);
FORCEPROP 2 LAST CDS_XR_PAGE_TITLE CR-292 : @S9S_MB_2U_LIB.S9S_MB_2U(SCH_1):PAGE292
J 0
(210 8100);
DISPLAY 0.638298 (210 8100);
PAINT PINK (210 8100);
DISPLAY INVISIBLE (210 8100);
FORCEPROP 2 LAST CDS_LIB pure_quanta
J 0
(8100 2850);
DISPLAY INVISIBLE (8100 2850);
FORCEPROP 1 LAST CDS_LMAN_SYM_OUTLINE -9475,6775,100,-125
J 0
(8100 2850);
DISPLAY 0.468085 (8100 2850);
PAINT GREEN (8100 2850);
DISPLAY INVISIBLE (8100 2850);
FORCEPROP 2 LAST PAGE_BORDER TRUE
J 0
(210 8100);
DISPLAY 0.638298 (210 8100);
PAINT PINK (210 8100);
DISPLAY INVISIBLE (210 8100);
FORCEPROP 1 LAST COMMENT_BODY TRUE
J 0
(8112 2837);
DISPLAY 0.978723 (8112 2837);
PAINT GREEN (8112 2837);
DISPLAY INVISIBLE (8112 2837);
FORCEADD DNS..1
(4475 8950);
PAINT RED (4475 8950);
FORCEPROP 1 LAST COMMENT_BODY TRUE
R 1
J 0
(4550 8725);
DISPLAY 0.872340 (4550 8725);
PAINT GREEN (4550 8725);
DISPLAY INVISIBLE (4550 8725);
FORCEPROP 2 LAST CDS_LIB mstr_misc
J 0
(4475 8950);
DISPLAY INVISIBLE (4475 8950);
FORCEADD DNS..2
(-75 8800);
PAINT RED (-75 8800);
FORCEPROP 1 LAST COMMENT_BODY TRUE
R 1
J 0
(0 8575);
DISPLAY 0.872340 (0 8575);
PAINT GREEN (0 8575);
DISPLAY INVISIBLE (0 8575);
FORCEPROP 2 LAST CDS_LIB mstr_misc
J 0
(-75 8800);
DISPLAY INVISIBLE (-75 8800);
FORCEADD DNS..2
(-75 8900);
PAINT RED (-75 8900);
FORCEPROP 1 LAST COMMENT_BODY TRUE
R 1
J 0
(0 8675);
DISPLAY 0.872340 (0 8675);
PAINT GREEN (0 8675);
DISPLAY INVISIBLE (0 8675);
FORCEPROP 2 LAST CDS_LIB mstr_misc
J 0
(-75 8900);
DISPLAY INVISIBLE (-75 8900);
FORCEADD DNS..1
(1100 3825);
PAINT RED (1100 3825);
FORCEPROP 1 LAST COMMENT_BODY TRUE
R 1
J 0
(1175 3600);
DISPLAY 0.872340 (1175 3600);
PAINT GREEN (1175 3600);
DISPLAY INVISIBLE (1175 3600);
FORCEPROP 2 LAST CDS_LIB mstr_misc
J 0
(1100 3825);
DISPLAY INVISIBLE (1100 3825);
FORCEADD DNS..2
(525 4050);
PAINT RED (525 4050);
FORCEPROP 1 LAST COMMENT_BODY TRUE
R 1
J 0
(600 3825);
DISPLAY 0.872340 (600 3825);
PAINT GREEN (600 3825);
DISPLAY INVISIBLE (600 3825);
FORCEPROP 2 LAST CDS_LIB mstr_misc
J 0
(525 4050);
PAINT MONO (525 4050);
DISPLAY INVISIBLE (525 4050);
FORCEADD DNS..1
(1900 3500);
PAINT RED (1900 3500);
FORCEPROP 1 LAST COMMENT_BODY TRUE
R 1
J 0
(1975 3275);
DISPLAY 0.872340 (1975 3275);
PAINT GREEN (1975 3275);
DISPLAY INVISIBLE (1975 3275);
FORCEPROP 2 LAST CDS_LIB mstr_misc
J 0
(1900 3500);
DISPLAY INVISIBLE (1900 3500);
FORCEADD DNS..1
(2300 3475);
PAINT RED (2300 3475);
FORCEPROP 1 LAST COMMENT_BODY TRUE
R 1
J 0
(2375 3250);
DISPLAY 0.872340 (2375 3250);
PAINT GREEN (2375 3250);
DISPLAY INVISIBLE (2375 3250);
FORCEPROP 2 LAST CDS_LIB mstr_misc
J 0
(2300 3475);
DISPLAY INVISIBLE (2300 3475);
FORCEADD DNS..1
(2150 4525);
PAINT RED (2150 4525);
FORCEPROP 1 LAST COMMENT_BODY TRUE
R 1
J 0
(2225 4300);
DISPLAY 0.872340 (2225 4300);
PAINT GREEN (2225 4300);
DISPLAY INVISIBLE (2225 4300);
FORCEPROP 2 LAST CDS_LIB mstr_misc
J 0
(2150 4525);
DISPLAY INVISIBLE (2150 4525);
FORCEADD DNS..1
(5175 3750);
PAINT RED (5175 3750);
FORCEPROP 1 LAST COMMENT_BODY TRUE
R 1
J 0
(5250 3525);
DISPLAY 0.872340 (5250 3525);
PAINT GREEN (5250 3525);
DISPLAY INVISIBLE (5250 3525);
FORCEPROP 2 LAST CDS_LIB mstr_misc
J 0
(5175 3750);
DISPLAY INVISIBLE (5175 3750);
FORCEADD DNS..1
(6700 4025);
PAINT RED (6700 4025);
FORCEPROP 1 LAST COMMENT_BODY TRUE
R 1
J 0
(6775 3800);
DISPLAY 0.872340 (6775 3800);
PAINT GREEN (6775 3800);
DISPLAY INVISIBLE (6775 3800);
FORCEPROP 2 LAST CDS_LIB mstr_misc
J 0
(6700 4025);
DISPLAY INVISIBLE (6700 4025);
FORCEADD DNS..1
(4825 8950);
PAINT RED (4825 8950);
FORCEPROP 1 LAST COMMENT_BODY TRUE
R 1
J 0
(4900 8725);
DISPLAY 0.872340 (4900 8725);
PAINT GREEN (4900 8725);
DISPLAY INVISIBLE (4900 8725);
FORCEPROP 2 LAST CDS_LIB mstr_misc
J 0
(4825 8950);
DISPLAY INVISIBLE (4825 8950);
FORCEADD DNS..1
(2025 9325);
PAINT RED (2025 9325);
FORCEPROP 1 LAST COMMENT_BODY TRUE
R 1
J 0
(2100 9100);
DISPLAY 0.872340 (2100 9100);
PAINT GREEN (2100 9100);
DISPLAY INVISIBLE (2100 9100);
FORCEPROP 2 LAST CDS_LIB mstr_misc
J 0
(2025 9325);
DISPLAY INVISIBLE (2025 9325);
WIRE 16 -1 (1050 7400)(1050 7300);
WIRE 16 -1 (-825 8900)(-825 8975);
WIRE 16 -1 (-375 8900)(-825 8900);
WIRE 16 -1 (825 3800)(825 3875);
WIRE 16 -1 (825 3700)(825 3800);
WIRE 16 -1 (1000 3800)(825 3800);
WIRE 16 -1 (875 4500)(875 4550);
WIRE 16 -1 (875 4500)(1250 4500);
WIRE 16 -1 (1025 5225)(1025 5150);
WIRE 16 -1 (1050 6300)(1050 6200);
WIRE 16 -1 (6275 5100)(6275 5000);
WIRE 16 -1 (750 9300)(750 9350);
WIRE 16 -1 (750 9300)(1075 9300);
WIRE 16 -1 (6000 9225)(6000 9150);
WIRE 16 -1 (625 3725)(625 3650);
WIRE 16 -1 (1875 3300)(1875 3250);
WIRE 16 -1 (1550 3300)(1875 3300);
WIRE 16 -1 (1875 3400)(1875 3300);
WIRE 16 -1 (2625 3300)(2625 3250);
WIRE 16 -1 (2300 3300)(2625 3300);
WIRE 16 -1 (2625 3400)(2625 3300);
WIRE 16 -1 (2800 3525)(2800 3600);
WIRE 16 -1 (2250 4500)(2800 4500);
WIRE 16 -1 (2250 4625)(2800 4625);
WIRE 16 -1 (1025 5525)(1025 5475);
WIRE 16 -1 (1025 5525)(650 5525);
WIRE 16 -1 (1025 6625)(1025 6575);
WIRE 16 -1 (1025 6625)(650 6625);
WIRE 16 -1 (2100 8875)(2675 8875);
WIRE 16 -1 (4375 3600)(4375 3675);
WIRE 16 -1 (5100 3550)(5100 3650);
WIRE 16 -1 (4800 4400)(5375 4400);
WIRE 16 -1 (6700 3850)(6700 3950);
WIRE 16 -1 (5975 5350)(5975 5325);
WIRE 16 -1 (5450 5350)(5975 5350);
WIRE 16 -1 (5975 5800)(5975 5775);
WIRE 16 -1 (5450 5800)(5975 5800);
WIRE 16 -1 (5975 6250)(5975 6225);
WIRE 16 -1 (5450 6250)(5975 6250);
WIRE 16 -1 (5975 6700)(5975 6675);
WIRE 16 -1 (5450 6700)(5975 6700);
WIRE 16 -1 (5975 7150)(5975 7125);
WIRE 16 -1 (5450 7150)(5975 7150);
WIRE 16 -1 (5600 8275)(5200 8275);
WIRE 16 -1 (5600 8750)(5200 8750);
WIRE 16 -1 (2125 9300)(2675 9300);
WIRE 16 -1 (1625 6050)(1975 6050);
WIRE 16 -1 (1975 5975)(1975 6050);
WIRE 16 -1 (2875 6000)(2675 6000);
WIRE 16 -1 (2675 6050)(1975 6050);
FORCEPROP 2 LAST SIG_NAME SH_PVCCFA_EHV_CPU1_R
J 0
(2065 6060);
DISPLAY 0.617021 (2065 6060);
WIRE 16 -1 (2675 6050)(2675 6000);
WIRE 17 273 (6300 7925)(8054 7925);
WIRE 17 273 (8054 9375)(8054 7925);
WIRE 17 273 (6300 9375)(6300 7925);
WIRE 17 273 (6300 9375)(8054 9375);
WIRE 17 273 (6300 7875)(8050 7875);
WIRE 17 273 (8050 7875)(8050 6475);
WIRE 17 273 (6300 7875)(6300 6475);
WIRE 17 273 (6300 6475)(8050 6475);
WIRE 16 -1 (2675 5750)(2875 5750);
WIRE 16 -1 (2675 5675)(2675 5750);
WIRE 16 -1 (1975 5775)(1975 5675);
WIRE 16 -1 (2675 5675)(1975 5675);
WIRE 16 -1 (-675 5675)(250 5675);
FORCEPROP 2 LAST SIG_NAME VSENSE_PVCCFA_EHV_CPU1_DN
J 0
(-585 5685);
DISPLAY 0.617021 (-585 5685);
WIRE 16 -1 (250 5675)(1975 5675);
WIRE 16 -1 (250 5525)(450 5525);
WIRE 16 -1 (250 5525)(250 5675);
WIRE 16 -1 (1450 4750)(1825 4750);
WIRE 16 -1 (1825 4750)(2875 4750);
FORCEPROP 2 LAST SIG_NAME PVCCFA_EHV_CPU1_EN_R
J 0
(1915 4760);
DISPLAY 0.617021 (1915 4760);
WIRE 16 -1 (1825 4750)(1825 4625);
WIRE 16 -1 (1825 4625)(2050 4625);
WIRE 16 -1 (1275 8000)(2875 8000);
FORCEPROP 2 LAST SIG_NAME SMB_CLK_PVCCINFAON_CPU1
J 0
(1840 8010);
DISPLAY 0.617021 (1840 8010);
WIRE 16 -1 (1275 8550)(2875 8550);
FORCEPROP 2 LAST SIG_NAME SVID_DIO_PVCCINFAON_CPU1_R
J 0
(1840 8560);
DISPLAY 0.617021 (1840 8560);
WIRE 16 -1 (1275 8400)(2875 8400);
FORCEPROP 2 LAST SIG_NAME SVID_ALERT_PVCCINFAON_CPU1_R
J 0
(1840 8410);
DISPLAY 0.617021 (1840 8410);
WIRE 16 -1 (1450 4350)(1825 4350);
WIRE 16 -1 (1825 4350)(2875 4350);
FORCEPROP 2 LAST SIG_NAME PWRGD_PVCCFA_EHV_CPU1_R
J 0
(1915 4360);
DISPLAY 0.617021 (1915 4360);
WIRE 16 -1 (1825 4500)(1450 4500);
WIRE 16 -1 (1825 4500)(1825 4350);
WIRE 16 -1 (2050 4500)(1825 4500);
WIRE 16 -1 (1275 8700)(2875 8700);
FORCEPROP 2 LAST SIG_NAME SVID_CLK_PVCCINFAON_CPU1_R
J 0
(1840 8710);
DISPLAY 0.617021 (1840 8710);
WIRE 16 -1 (1775 7700)(2875 7700);
FORCEPROP 2 LAST SIG_NAME NC_PVCCINFAON_CPU1_SMB_ALERT
J 0
(1840 7710);
DISPLAY 0.617021 (1840 7710);
WIRE 16 -1 (1275 9000)(1700 9000);
WIRE 16 -1 (1700 9000)(2875 9000);
FORCEPROP 2 LAST SIG_NAME PVCCINFAON_CPU1_EN_R
J 0
(1840 9010);
DISPLAY 0.617021 (1840 9010);
WIRE 16 -1 (1700 9000)(1700 8875);
WIRE 16 -1 (1900 8875)(1700 8875);
WIRE 16 -1 (2875 6850)(2675 6850);
WIRE 16 -1 (2675 6775)(2675 6850);
WIRE 16 -1 (1975 6875)(1975 6775);
WIRE 16 -1 (2675 6775)(1975 6775);
WIRE 16 -1 (-675 6775)(250 6775);
FORCEPROP 2 LAST SIG_NAME VSENSE_PVCCINFAON_CPU1_DN
J 0
(-585 6785);
DISPLAY 0.617021 (-585 6785);
WIRE 16 -1 (250 6775)(1975 6775);
WIRE 16 -1 (250 6625)(450 6625);
WIRE 16 -1 (250 6625)(250 6775);
WIRE 16 -1 (1275 7850)(2875 7850);
FORCEPROP 2 LAST SIG_NAME SMB_DIO_PVCCINFAON_CPU1
J 0
(1840 7860);
DISPLAY 0.617021 (1840 7860);
WIRE 16 -1 (2875 7100)(2675 7100);
WIRE 16 -1 (2675 7150)(2675 7100);
WIRE 16 -1 (1975 7075)(1975 7150);
WIRE 16 -1 (2675 7150)(1975 7150);
FORCEPROP 2 LAST SIG_NAME SH_PVCCINFAON_CPU1_R
J 0
(2065 7160);
DISPLAY 0.617021 (2065 7160);
WIRE 16 -1 (1625 7150)(1975 7150);
WIRE 16 -1 (1700 9150)(1275 9150);
WIRE 16 -1 (1700 9150)(2875 9150);
FORCEPROP 2 LAST SIG_NAME PWRGD_PVCCINFAON_CPU1_R
J 0
(1840 9160);
DISPLAY 0.617021 (1840 9160);
WIRE 16 -1 (1700 9150)(1700 9300);
WIRE 16 -1 (1700 9300)(1275 9300);
WIRE 16 -1 (1925 9300)(1700 9300);
WIRE 16 -1 (1875 3600)(1875 3800);
WIRE 16 -1 (1875 3800)(2875 3800);
FORCEPROP 2 LAST SIG_NAME PVCCINFAON_CPU1_CSPIN
J 0
(1915 3810);
DISPLAY 0.617021 (1915 3810);
WIRE 16 -1 (1550 3600)(1550 3800);
WIRE 16 -1 (1875 3800)(1550 3800);
WIRE 16 -1 (1200 3800)(1550 3800);
WIRE 16 -1 (2625 3600)(2625 3700);
WIRE 16 -1 (2625 3700)(2875 3700);
WIRE 16 -1 (2300 3600)(2300 3700);
WIRE 16 -1 (2300 3700)(2625 3700);
WIRE 16 -1 (1200 3700)(2300 3700);
FORCEPROP 2 LAST SIG_NAME PVCCINFAON_CPU1_VIN_CSNIN
J 0
(1915 3710);
DISPLAY 0.617021 (1915 3710);
WIRE 16 -1 (1825 5050)(1450 5050);
WIRE 16 -1 (275 4900)(1825 4900);
WIRE 16 -1 (1825 4900)(1825 5050);
WIRE 16 -1 (1825 4900)(2875 4900);
FORCEPROP 2 LAST SIG_NAME PVCCINFAON_CPU1_PIN_ALERT
J 0
(1915 4910);
DISPLAY 0.617021 (1915 4910);
WIRE 16 -1 (1450 5150)(2875 5150);
FORCEPROP 2 LAST SIG_NAME PVCCINFAON_CPU1_VR_FAULT
J 0
(1915 5160);
DISPLAY 0.617021 (1915 5160);
WIRE 16 -1 (2800 3600)(2875 3600);
WIRE 16 -1 (600 4050)(625 4050);
WIRE 16 -1 (625 4050)(2875 4050);
FORCEPROP 2 LAST SIG_NAME PVCCINFAON_CPU1_ADDR
J 0
(1915 4060);
DISPLAY 0.617021 (1915 4060);
WIRE 16 -1 (625 3925)(625 4050);
WIRE 16 -1 (4225 4900)(5350 4900);
FORCEPROP 2 LAST SIG_NAME PVCCFA_EHV_CPU1_BCSP1
J 0
(4390 4910);
DISPLAY 0.617021 (4390 4910);
WIRE 16 -1 (5350 5000)(4225 5000);
FORCEPROP 2 LAST SIG_NAME PVCCFA_EHV_CPU1_BPWM1
J 0
(4390 5010);
DISPLAY 0.617021 (4390 5010);
WIRE 16 -1 (4225 3950)(4375 3950);
WIRE 16 -1 (4375 3875)(4375 3950);
WIRE 16 -1 (5100 3950)(4375 3950);
WIRE 16 -1 (6225 3950)(5100 3950);
FORCEPROP 2 LAST SIG_NAME PVCCINFAON_CPU1_ATSEN
J 0
(5340 3960);
DISPLAY 0.617021 (5340 3960);
WIRE 16 -1 (5100 3850)(5100 3950);
WIRE 16 -1 (4225 5800)(5250 5800);
FORCEPROP 2 LAST SIG_NAME NC_PVCCINFAON_CPU1_ACSP6
J 0
(4340 5810);
DISPLAY 0.617021 (4340 5810);
WIRE 16 -1 (5100 5900)(4225 5900);
FORCEPROP 2 LAST SIG_NAME NC_PVCCINFAON_CPU1_APWM6
J 0
(4340 5910);
DISPLAY 0.617021 (4340 5910);
WIRE 16 -1 (4225 6250)(5250 6250);
FORCEPROP 2 LAST SIG_NAME NC_PVCCINFAON_CPU1_ACSP5
J 0
(4340 6260);
DISPLAY 0.617021 (4340 6260);
WIRE 16 -1 (5100 6350)(4225 6350);
FORCEPROP 2 LAST SIG_NAME NC_PVCCINFAON_CPU1_APWM5
J 0
(4340 6360);
DISPLAY 0.617021 (4340 6360);
WIRE 16 -1 (4225 8150)(5325 8150);
FORCEPROP 2 LAST SIG_NAME PVCCINFAON_CPU1_APWM1
J 0
(4390 8160);
DISPLAY 0.617021 (4390 8160);
WIRE 16 -1 (4225 5350)(5250 5350);
FORCEPROP 2 LAST SIG_NAME NC_PVCCINFAON_CPU1_ACSP7
J 0
(4340 5360);
DISPLAY 0.617021 (4340 5360);
WIRE 16 -1 (4375 4400)(4600 4400);
WIRE 16 -1 (4375 4250)(4225 4250);
WIRE 16 -1 (4375 4250)(4375 4400);
WIRE 16 -1 (6700 4250)(4375 4250);
FORCEPROP 2 LAST SIG_NAME PVCCFA_EHV_CPU1_BTSEN
J 0
(6015 4260);
DISPLAY 0.617021 (6015 4260);
WIRE 16 -1 (6700 4150)(6700 4250);
WIRE 16 -1 (7000 4250)(6700 4250);
WIRE 16 -1 (5200 8575)(5200 8675);
WIRE 16 -1 (5200 8675)(5600 8675);
WIRE 16 -1 (4800 8575)(4800 8675);
WIRE 16 -1 (5200 8675)(4800 8675);
WIRE 16 -1 (4800 8675)(4375 8675);
FORCEPROP 2 LAST SIG_NAME PVCCINFAON_CPU1_VREF
J 0
(4415 8685);
DISPLAY 0.617021 (4415 8685);
WIRE 16 -1 (4375 8850)(4375 8675);
WIRE 16 -1 (4225 8850)(4375 8850);
WIRE 16 -1 (5325 7700)(4225 7700);
FORCEPROP 2 LAST SIG_NAME PVCCINFAON_CPU1_APWM2
J 0
(4390 7710);
DISPLAY 0.617021 (4390 7710);
WIRE 16 -1 (5100 5450)(4225 5450);
FORCEPROP 2 LAST SIG_NAME NC_PVCCINFAON_CPU1_APWM7
J 0
(4340 5460);
DISPLAY 0.617021 (4340 5460);
WIRE 16 -1 (5100 7250)(4225 7250);
FORCEPROP 2 LAST SIG_NAME NC_PVCCINFAON_CPU1_APWM3
J 0
(4340 7260);
DISPLAY 0.617021 (4340 7260);
WIRE 16 -1 (5100 6800)(4225 6800);
FORCEPROP 2 LAST SIG_NAME NC_PVCCINFAON_CPU1_APWM4
J 0
(4340 6810);
DISPLAY 0.617021 (4340 6810);
WIRE 16 -1 (4225 6700)(5250 6700);
FORCEPROP 2 LAST SIG_NAME NC_PVCCINFAON_CPU1_ACSP4
J 0
(4340 6710);
DISPLAY 0.617021 (4340 6710);
WIRE 16 -1 (4225 7150)(5250 7150);
FORCEPROP 2 LAST SIG_NAME NC_PVCCINFAON_CPU1_ACSP3
J 0
(4340 7160);
DISPLAY 0.617021 (4340 7160);
WIRE 16 -1 (4225 4650)(5575 4650);
FORCEPROP 2 LAST SIG_NAME IRQ_PVCCFA_CPU1_VRHOT_N
J 0
(4390 4660);
DISPLAY 0.617021 (4390 4660);
WIRE 16 -1 (5325 7600)(4225 7600);
FORCEPROP 2 LAST SIG_NAME PVCCINFAON_CPU1_ACSP2
J 0
(4390 7610);
DISPLAY 0.617021 (4390 7610);
WIRE 16 -1 (4225 9150)(4450 9150);
FORCEPROP 2 LAST SIG_NAME PVCCINFAON_CPU1_VCC
J 0
(4415 9160);
DISPLAY 0.617021 (4415 9160);
WIRE 16 -1 (4450 9050)(4450 9150);
WIRE 16 -1 (4450 9150)(4800 9150);
WIRE 16 -1 (4800 9050)(4800 9150);
WIRE 16 -1 (4800 9150)(5200 9150);
WIRE 16 -1 (5425 9150)(5200 9150);
WIRE 16 -1 (5200 9050)(5200 9150);
WIRE 16 -1 (4225 8050)(5325 8050);
FORCEPROP 2 LAST SIG_NAME PVCCINFAON_CPU1_ACSP1
J 0
(4390 8060);
DISPLAY 0.617021 (4390 8060);
WIRE 16 -1 (5775 4650)(6275 4650);
WIRE 16 -1 (7000 4650)(6275 4650);
FORCEPROP 2 LAST SIG_NAME IRQ_PVCCFA_CPU1_VRHOT_R_N
J 0
(6290 4660);
DISPLAY 0.617021 (6290 4660);
WIRE 16 -1 (6275 4800)(6275 4650);
WIRE 16 2175 (6200 4600)(7450 4600);
WIRE 16 2175 (7450 4700)(7450 4600);
WIRE 16 2175 (6200 4700)(6200 4600);
WIRE 16 2175 (6200 4700)(7450 4700);
WIRE 16 -1 (5200 8275)(5200 8375);
WIRE 16 -1 (4800 8275)(5200 8275);
WIRE 16 -1 (4800 8375)(4800 8275);
WIRE 16 -1 (5200 8850)(5200 8750);
WIRE 16 -1 (4800 8850)(4800 8750);
WIRE 16 -1 (4800 8750)(5200 8750);
WIRE 16 -1 (4450 8750)(4800 8750);
WIRE 16 -1 (4450 8850)(4450 8750);
WIRE 16 -1 (825 3700)(1000 3700);
WIRE 17 273 (-1125 3325)(800 3325);
WIRE 17 273 (800 3325)(800 3075);
WIRE 17 273 (-1125 3325)(-1125 3075);
WIRE 17 273 (-1125 3075)(800 3075);
WIRE 16 -1 (1250 4350)(275 4350);
FORCEPROP 2 LAST SIG_NAME PWRGD_PVCCFA_EHV_CPU1
J 0
(340 4360);
DISPLAY 0.617021 (340 4360);
WIRE 16 -1 (-400 4050)(400 4050);
FORCEPROP 2 LAST SIG_NAME PVCCINFAON_CPU1_VREF
J 0
(-360 4060);
DISPLAY 0.617021 (-360 4060);
WIRE 16 -1 (6000 9150)(5625 9150);
WIRE 16 -1 (600 7150)(1425 7150);
FORCEPROP 2 LAST SIG_NAME SH_PVCCINFAON_CPU1
J 0
(765 7160);
DISPLAY 0.617021 (765 7160);
WIRE 16 -1 (1050 7300)(650 7300);
WIRE 16 -1 (250 7300)(450 7300);
WIRE 16 -1 (350 7150)(250 7150);
WIRE 16 -1 (250 7150)(250 7300);
WIRE 16 -1 (-675 7150)(250 7150);
FORCEPROP 2 LAST SIG_NAME VSENSE_PVCCINFAON_CPU1_DP
J 0
(-585 7160);
DISPLAY 0.617021 (-585 7160);
WIRE 16 -1 (600 6050)(1425 6050);
FORCEPROP 2 LAST SIG_NAME SH_PVCCFA_EHV_CPU1
J 0
(690 6060);
DISPLAY 0.617021 (690 6060);
WIRE 16 -1 (1050 6200)(650 6200);
WIRE 16 -1 (250 6200)(450 6200);
WIRE 16 -1 (350 6050)(250 6050);
WIRE 16 -1 (250 6050)(250 6200);
WIRE 16 -1 (-675 6050)(250 6050);
FORCEPROP 2 LAST SIG_NAME VSENSE_PVCCFA_EHV_CPU1_DP
J 0
(-585 6060);
DISPLAY 0.617021 (-585 6060);
WIRE 16 -1 (1250 5050)(1025 5050);
WIRE 16 -1 (1025 5150)(1025 5050);
WIRE 16 -1 (1250 5150)(1025 5150);
WIRE 16 -1 (2300 3400)(2300 3300);
WIRE 16 -1 (1550 3400)(1550 3300);
WIRE 16 -1 (275 4750)(1250 4750);
FORCEPROP 2 LAST SIG_NAME FM_PVCCFA_EHV_CPU1_EN
J 0
(340 4760);
DISPLAY 0.617021 (340 4760);
WIRE 16 -1 (-75 8400)(1075 8400);
FORCEPROP 2 LAST SIG_NAME SVID_ALERT0_CPU1_R_N
J 0
(15 8410);
DISPLAY 0.617021 (15 8410);
WIRE 16 -1 (-75 9150)(1075 9150);
FORCEPROP 2 LAST SIG_NAME PWRGD_PVCCINFAON_CPU1
J 0
(15 9160);
DISPLAY 0.617021 (15 9160);
WIRE 16 -1 (575 8800)(0 8800);
WIRE 16 -1 (575 8550)(-75 8550);
FORCEPROP 2 LAST SIG_NAME SVID_DIO0_CPU1_R
J 0
(15 8560);
DISPLAY 0.617021 (15 8560);
WIRE 16 -1 (575 8550)(575 8800);
WIRE 16 -1 (1075 8550)(575 8550);
WIRE 16 -1 (1075 7850)(-125 7850);
FORCEPROP 2 LAST SIG_NAME SMB_VR_3V3AUX_SDA_R
J 0
(-60 7860);
DISPLAY 0.617021 (-60 7860);
WIRE 16 -1 (0 8900)(650 8900);
WIRE 16 -1 (650 8700)(650 8900);
WIRE 16 -1 (1075 8700)(650 8700);
WIRE 16 -1 (-75 8700)(650 8700);
FORCEPROP 2 LAST SIG_NAME SVID_CLK0_CPU1_R
J 0
(15 8710);
DISPLAY 0.617021 (15 8710);
WIRE 16 -1 (-75 9000)(1075 9000);
FORCEPROP 2 LAST SIG_NAME FM_PVCCINFAON_CPU1_EN
J 0
(15 9010);
DISPLAY 0.617021 (15 9010);
WIRE 16 -1 (-125 8000)(1075 8000);
FORCEPROP 2 LAST SIG_NAME SMB_VR_3V3AUX_SCL_R
J 0
(-60 8010);
DISPLAY 0.617021 (-60 8010);
WIRE 16 -1 (-375 8800)(-200 8800);
WIRE 16 -1 (-375 8800)(-375 8900);
WIRE 16 -1 (-375 8900)(-200 8900);
WIRE 17 273 (-650 7250)(-650 6700);
WIRE 17 273 (-925 7250)(-650 7250);
WIRE 17 273 (-925 6700)(-650 6700);
WIRE 17 273 (-925 6700)(-925 7250);
WIRE 17 273 (-650 6150)(-650 5600);
WIRE 17 273 (-925 6150)(-650 6150);
WIRE 17 273 (-925 5600)(-650 5600);
WIRE 17 273 (-925 5600)(-925 6150);
CIRCLE (-50 4900)(95 4900);
PAINT YELLOW (-50 4900);
DOT 1 (-375 8900);
DOT 1 (825 3800);
DOT 1 (625 4050);
DOT 1 (1550 3800);
DOT 1 (1875 3300);
DOT 1 (1875 3800);
DOT 1 (1825 4500);
DOT 1 (1825 4350);
DOT 1 (1825 4750);
DOT 1 (2625 3300);
DOT 1 (2300 3700);
DOT 1 (2625 3700);
DOT 1 (250 5675);
DOT 1 (1025 5150);
DOT 1 (250 6050);
DOT 1 (250 6775);
DOT 1 (1825 4900);
DOT 1 (1975 5675);
DOT 1 (1975 6050);
DOT 1 (1975 6775);
DOT 1 (250 7150);
DOT 1 (575 8550);
DOT 1 (650 8700);
DOT 1 (1975 7150);
DOT 1 (4375 3950);
DOT 1 (4375 4250);
DOT 1 (5100 3950);
DOT 1 (6275 4650);
DOT 1 (6700 4250);
DOT 1 (4800 8675);
DOT 1 (5200 8275);
DOT 1 (5200 8675);
DOT 1 (5200 8750);
DOT 1 (1700 9000);
DOT 1 (1700 9150);
DOT 1 (1700 9300);
DOT 1 (4800 9150);
DOT 1 (5200 9150);
DOT 1 (4450 9150);
DOT 1 (4800 8750);
FORCENOTE
SLEW RATE=18A/US(EMR 20.2A/US)
(6350 8450) 0;
DISPLAY LEFT (6350 8450);
DISPLAY 0.936170 (6350 8450);
PAINT RED (6350 8450);
FORCENOTE
CURRENT STEP=15A(38A-53A)(EMR 31A-46A)
(6350 8525) 0;
DISPLAY LEFT (6350 8525);
DISPLAY 0.936170 (6350 8525);
PAINT RED (6350 8525);
FORCENOTE
LOAD-LINE=2.2 MOHM
(6345 8368) 0;
DISPLAY LEFT (6345 8368);
DISPLAY 0.936170 (6345 8368);
PAINT RED (6345 8368);
FORCENOTE
WORK FREQUENCY=700KHZ
(6350 8300) 0;
DISPLAY LEFT (6350 8300);
DISPLAY 0.936170 (6350 8300);
PAINT WHITE (6350 8300);
FORCENOTE
SVID ADDRESS=01H BUS#0
(6350 8225) 0;
DISPLAY LEFT (6350 8225);
DISPLAY 0.936170 (6350 8225);
PAINT WHITE (6350 8225);
FORCENOTE
PROTOCOL ID=09H (VR14 5MV VID)
(6345 8138) 0;
DISPLAY LEFT (6345 8138);
DISPLAY 0.936170 (6345 8138);
PAINT WHITE (6345 8138);
FORCENOTE
SETVID RATE=2.5MV/US (FAST)
(6350 8050) 0;
DISPLAY LEFT (6350 8050);
DISPLAY 0.936170 (6350 8050);
PAINT WHITE (6350 8050);
FORCENOTE
PDG REV.1.6 FOR SPR+HBM
(6345 7968) 0;
DISPLAY LEFT (6345 7968);
DISPLAY 0.936170 (6345 7968);
PAINT RED (6345 7968);
FORCENOTE
OCP=69A(130%)
(6350 8600) 0;
DISPLAY LEFT (6350 8600);
DISPLAY 0.936170 (6350 8600);
PAINT RED (6350 8600);
FORCENOTE
MAX CURRENT=53A(EMR 46A)
(6349 8678) 0;
DISPLAY LEFT (6349 8678);
DISPLAY 0.936170 (6349 8678);
PAINT RED (6349 8678);
FORCENOTE
PVCCFA_EHV_CPU1 SPECIFICATION
(6325 7800) 0;
DISPLAY LEFT (6325 7800);
DISPLAY 1.021277 (6325 7800);
PAINT WHITE (6325 7800);
FORCENOTE
VBOOT=1.8V
(6329 7692) 0;
DISPLAY LEFT (6329 7692);
DISPLAY 0.936170 (6329 7692);
PAINT WHITE (6329 7692);
FORCENOTE
VID=1.6V~1.87V(TYP=1.8V)
(6329 7617) 0;
DISPLAY LEFT (6329 7617);
DISPLAY 0.936170 (6329 7617);
PAINT WHITE (6329 7617);
FORCENOTE
RIPPLE=+/-9MV
(6329 7542) 0;
DISPLAY LEFT (6329 7542);
DISPLAY 0.936170 (6329 7542);
PAINT RED (6329 7542);
FORCENOTE
DC=+/-0.5% OF VID
(6329 7475) 0;
DISPLAY LEFT (6329 7475);
DISPLAY 0.936170 (6329 7475);
PAINT WHITE (6329 7475);
FORCENOTE
TOTAL TOLERANCE=1.841VMAX/1.749VMIN
(6329 7391) 0;
DISPLAY LEFT (6329 7391);
DISPLAY 0.936170 (6329 7391);
PAINT RED (6329 7391);
FORCENOTE
MAX CURRENT=6.25A
(6334 7242) 0;
DISPLAY LEFT (6334 7242);
DISPLAY 0.936170 (6334 7242);
PAINT RED (6334 7242);
FORCENOTE
OCP=15A
(6334 7167) 0;
DISPLAY LEFT (6334 7167);
DISPLAY 0.936170 (6334 7167);
PAINT WHITE (6334 7167);
FORCENOTE
20220725 CONNECT TO CPLD
(6550 4725) 0;
DISPLAY LEFT (6550 4725);
DISPLAY 0.680851 (6550 4725);
PAINT WHITE (6550 4725);
FORCENOTE
PVCCFA_EHV_CPU1
(-1100 3125) 0;
DISPLAY LEFT (-1100 3125);
DISPLAY 0.638298 (-1100 3125);
PAINT WHITE (-1100 3125);
FORCENOTE
PVCCINFAON_CPU1
(-1100 3200) 0;
DISPLAY LEFT (-1100 3200);
DISPLAY 0.638298 (-1100 3200);
PAINT WHITE (-1100 3200);
FORCENOTE
RAIL
(-950 3250) 0;
DISPLAY LEFT (-950 3250);
DISPLAY 0.808511 (-950 3250);
PAINT WHITE (-950 3250);
FORCENOTE
SVID
(-575 3250) 0;
DISPLAY LEFT (-575 3250);
DISPLAY 0.808511 (-575 3250);
PAINT WHITE (-575 3250);
FORCENOTE
02H
(-550 3125) 0;
DISPLAY LEFT (-550 3125);
DISPLAY 0.638298 (-550 3125);
PAINT WHITE (-550 3125);
FORCENOTE
01H
(-550 3200) 0;
DISPLAY LEFT (-550 3200);
DISPLAY 0.638298 (-550 3200);
PAINT WHITE (-550 3200);
FORCENOTE
74H/E8H
(-250 3125) 0;
DISPLAY LEFT (-250 3125);
DISPLAY 0.638298 (-250 3125);
PAINT WHITE (-250 3125);
FORCENOTE
74H/E8H
(-250 3200) 0;
DISPLAY LEFT (-250 3200);
DISPLAY 0.638298 (-250 3200);
PAINT WHITE (-250 3200);
FORCENOTE
DIFFERENTIAL PAIR
(-925 5475) 0;
DISPLAY LEFT (-925 5475);
DISPLAY 1.021277 (-925 5475);
PAINT WHITE (-925 5475);
FORCENOTE
TRACE WIDTH = 10MIL
(-925 5400) 0;
DISPLAY LEFT (-925 5400);
DISPLAY 1.021277 (-925 5400);
PAINT WHITE (-925 5400);
FORCENOTE
TRACE SPACING = 5MIL
(-925 6425) 0;
DISPLAY LEFT (-925 6425);
DISPLAY 1.021277 (-925 6425);
PAINT WHITE (-925 6425);
FORCENOTE
TRACE WIDTH = 10MIL
(-925 6500) 0;
DISPLAY LEFT (-925 6500);
DISPLAY 1.021277 (-925 6500);
PAINT WHITE (-925 6500);
FORCENOTE
DIFFERENTIAL PAIR
(-925 6575) 0;
DISPLAY LEFT (-925 6575);
DISPLAY 1.021277 (-925 6575);
PAINT WHITE (-925 6575);
FORCENOTE
TRACE SPACING = 5MIL
(-925 5325) 0;
DISPLAY LEFT (-925 5325);
DISPLAY 1.021277 (-925 5325);
PAINT WHITE (-925 5325);
FORCENOTE
SET FW CODE FUNCTION TO BVR_EN
(-400 4975) 0;
DISPLAY LEFT (-400 4975);
DISPLAY 1.021277 (-400 4975);
PAINT SKYBLUE (-400 4975);
FORCENOTE
CONFIRM ADDRESS SETTING
(725 4150) 0;
DISPLAY LEFT (725 4150);
DISPLAY 1.021277 (725 4150);
PAINT SKYBLUE (725 4150);
FORCENOTE
I2C(7BIT/8BIT)
(-250 3250) 0;
DISPLAY LEFT (-250 3250);
DISPLAY 0.808511 (-250 3250);
PAINT WHITE (-250 3250);
FORCENOTE
SVID / I2C ADDRESS
(-1075 3375) 0;
DISPLAY LEFT (-1075 3375);
DISPLAY 1.170213 (-1075 3375);
PAINT WHITE (-1075 3375);
FORCENOTE
20220808 UPDATE PDG REV 1.6
(6050 6350) 0;
DISPLAY LEFT (6050 6350);
DISPLAY 1.595745 (6050 6350);
FORCENOTE
SLEW RATE=5.3A
(6334 7007) 0;
DISPLAY LEFT (6334 7007);
DISPLAY 0.936170 (6334 7007);
PAINT RED (6334 7007);
FORCENOTE
TDC=5A
(6334 7317) 0;
DISPLAY LEFT (6334 7317);
DISPLAY 0.936170 (6334 7317);
PAINT RED (6334 7317);
FORCENOTE
LOAD-LINE=N/A
(6334 6932) 0;
DISPLAY LEFT (6334 6932);
DISPLAY 0.936170 (6334 6932);
PAINT WHITE (6334 6932);
FORCENOTE
CURRENT STEP=4.75A(1.5A-6.25A)
(6334 7092) 0;
DISPLAY LEFT (6334 7092);
DISPLAY 0.936170 (6334 7092);
PAINT RED (6334 7092);
FORCENOTE
PROTOCOL ID=04H (VR13 10MV VID)
(6329 6695) 0;
DISPLAY LEFT (6329 6695);
DISPLAY 0.936170 (6329 6695);
PAINT WHITE (6329 6695);
FORCENOTE
SETVID RATE=10MV/US (FAST)
(6334 6607) 0;
DISPLAY LEFT (6334 6607);
DISPLAY 0.936170 (6334 6607);
PAINT WHITE (6334 6607);
FORCENOTE
SVID ADDRESS=02H BUS#0
(6334 6782) 0;
DISPLAY LEFT (6334 6782);
DISPLAY 0.936170 (6334 6782);
PAINT WHITE (6334 6782);
FORCENOTE
WORK FREQUENCY=600KHZ
(6334 6857) 0;
DISPLAY LEFT (6334 6857);
DISPLAY 0.936170 (6334 6857);
PAINT WHITE (6334 6857);
FORCENOTE
PDG REV.1.6 FOR SPR+HBM
(6325 6525) 0;
DISPLAY LEFT (6325 6525);
DISPLAY 0.936170 (6325 6525);
PAINT RED (6325 6525);
FORCENOTE
VBOOT=1.0V
(6350 9192) 0;
DISPLAY LEFT (6350 9192);
DISPLAY 0.936170 (6350 9192);
PAINT WHITE (6350 9192);
FORCENOTE
RIPPLE=+/-8MV
(6350 9042) 0;
DISPLAY LEFT (6350 9042);
DISPLAY 0.936170 (6350 9042);
PAINT RED (6350 9042);
FORCENOTE
DC=+/-0.5%@1V
(6350 8970) 0;
DISPLAY LEFT (6350 8970);
DISPLAY 0.936170 (6350 8970);
PAINT WHITE (6350 8970);
FORCENOTE
TDC=48A(EMR 42A)
(6350 8750) 0;
DISPLAY LEFT (6350 8750);
DISPLAY 0.936170 (6350 8750);
PAINT RED (6350 8750);
FORCENOTE
PVCCINFAON_CPU1 SPECIFICATION
(6350 9295) 0;
DISPLAY LEFT (6350 9295);
DISPLAY 1.021277 (6350 9295);
PAINT WHITE (6350 9295);
FORCENOTE
VID=0.7V~1.05V(TYP=1.0V)
(6350 9117) 0;
DISPLAY LEFT (6350 9117);
DISPLAY 0.936170 (6350 9117);
PAINT WHITE (6350 9117);
FORCENOTE
TOTAL TOLERANCE=1.05VMAX/0.909VMIN
(6350 8891) 0;
DISPLAY LEFT (6350 8891);
DISPLAY 0.936170 (6350 8891);
PAINT RED (6350 8891);
FORCENOTE
(EMR 1.05VAMX/0.93VMIN)
(6350 8825) 0;
DISPLAY LEFT (6350 8825);
DISPLAY 0.936170 (6350 8825);
PAINT RED (6350 8825);
QUIT
